FILE_TYPE = MACRO_DRAWING;
SET COLOR_WIRE YELLOW;
SET COLOR_PROP MONO;
SET COLOR_DOT WHITE;
SET COLOR_ARC YELLOW;
SET COLOR_BODY GREEN;
SET COLOR_NOTE MONO;
SET PROP_DISPLAY VALUE;
SET PAGE_NUMBER P86;
FORCEADD GND..1
R 2
(-3525 1525);
FORCEPROP 3 LASTPIN (-3525 1575) SIG_NAME GND\g
J 0
(-3515 1585);
DISPLAY 0.659574 (-3515 1585);
PAINT MONO (-3515 1585);
DISPLAY INVISIBLE (-3515 1585);
FORCEPROP 1 LAST VOLTAGE 0
J 0
(-3525 1525);
PAINT SKYBLUE (-3525 1525);
DISPLAY INVISIBLE (-3525 1525);
FORCEPROP 2 LAST CDS_LIB mstr_symbols
J 0
(-3525 1525);
DISPLAY 0.787234 (-3525 1525);
PAINT MONO (-3525 1525);
DISPLAY INVISIBLE (-3525 1525);
FORCEPROP 1 LAST SIZE 1B
J 2
(-3600 1475);
DISPLAY 1.170213 (-3600 1475);
PAINT GREEN (-3600 1475);
DISPLAY INVISIBLE (-3600 1475);
FORCEPROP 2 LAST BOM_COST MEM
J 0
(-3525 1530);
PAINT ORANGE (-3525 1530);
DISPLAY INVISIBLE (-3525 1530);
FORCEPROP 1 LAST BODY_TYPE PLUMBING
J 2
(-3480 1482);
DISPLAY 0.340426 (-3480 1482);
PAINT GREEN (-3480 1482);
DISPLAY INVISIBLE (-3480 1482);
FORCEPROP 1 LAST PATH I1
J 2
(-3600 1525);
DISPLAY 0.872340 (-3600 1525);
PAINT AQUA (-3600 1525);
DISPLAY INVISIBLE (-3600 1525);
FORCEPROP 2 LAST ROOM DDR4_CH_D
J 0
(-3525 1530);
PAINT ORANGE (-3525 1530);
DISPLAY INVISIBLE (-3525 1530);
FORCEPROP 1 LAST HDL_POWER GND
J 2
(-3525 1675);
DISPLAY 0.553191 (-3525 1675);
PAINT GREEN (-3525 1675);
DISPLAY INVISIBLE (-3525 1675);
FORCEADD OFFPAGE..1
(-2225 1525);
FORCEPROP 2 LAST $XR5 88 
J 0
(-2926 1525);
DISPLAY 0.638298 (-2926 1525);
PAINT MONO (-2926 1525);
FORCEPROP 2 LAST $XR4 87 
J 0
(-2836 1525);
DISPLAY 0.638298 (-2836 1525);
PAINT MONO (-2836 1525);
FORCEPROP 2 LAST $XR3 85 
J 0
(-2746 1525);
DISPLAY 0.638298 (-2746 1525);
PAINT MONO (-2746 1525);
FORCEPROP 2 LAST $XR2 84 
J 0
(-2656 1525);
DISPLAY 0.638298 (-2656 1525);
PAINT MONO (-2656 1525);
FORCEPROP 2 LAST $XR1 83 
J 0
(-2566 1525);
DISPLAY 0.638298 (-2566 1525);
PAINT MONO (-2566 1525);
FORCEPROP 2 LAST $XR0 99 
J 0
(-2476 1525);
DISPLAY 0.638298 (-2476 1525);
PAINT MONO (-2476 1525);
FORCEPROP 2 LAST CDS_LIB mstr_standard
J 0
(-2225 1525);
DISPLAY 0.787234 (-2225 1525);
PAINT MONO (-2225 1525);
DISPLAY INVISIBLE (-2225 1525);
FORCEPROP 1 LAST OFFPAGE TRUE
J 0
(-1900 1400);
DISPLAY 0.936170 (-1900 1400);
PAINT GREEN (-1900 1400);
DISPLAY INVISIBLE (-1900 1400);
FORCEPROP 1 LAST COMMENT_BODY TRUE
J 0
(-2100 1425);
DISPLAY 0.936170 (-2100 1425);
PAINT GREEN (-2100 1425);
DISPLAY INVISIBLE (-2100 1425);
FORCEPROP 2 LAST PATH I10
J 0
(-2475 1575);
DISPLAY 1.021277 (-2475 1575);
PAINT ORANGE (-2475 1575);
DISPLAY INVISIBLE (-2475 1575);
FORCEADD SCONN288_H44441003..2
(1625 3975);
FORCEPROP 1 LAST PART_NUMBER H44441-003
J 0
(1225 2875);
DISPLAY 0.617021 (1225 2875);
PAINT BLUE (1225 2875);
FORCEPROP 1 LAST MATERIAL SCONN
J 0
(1225 5025);
DISPLAY 0.617021 (1225 5025);
PAINT SKYBLUE (1225 5025);
FORCEPROP 2 LASTPIN (2075 4825) $PN 51
J 0
(2085 4835);
DISPLAY 0.617021 (2085 4835);
PAINT ORANGE (2085 4835);
FORCEPROP 2 LASTPIN (2075 4775) $PN 52
J 0
(2085 4785);
DISPLAY 0.617021 (2085 4785);
PAINT ORANGE (2085 4785);
FORCEPROP 2 LASTPIN (2075 4725) $PN 132
J 0
(2085 4735);
DISPLAY 0.617021 (2085 4735);
PAINT ORANGE (2085 4735);
FORCEPROP 2 LASTPIN (2075 4675) $PN 133
J 0
(2085 4685);
DISPLAY 0.617021 (2085 4685);
PAINT ORANGE (2085 4685);
FORCEPROP 2 LASTPIN (2075 4625) $PN 121
J 0
(2085 4635);
DISPLAY 0.617021 (2085 4635);
PAINT ORANGE (2085 4635);
FORCEPROP 2 LASTPIN (2075 4575) $PN 122
J 0
(2085 4585);
DISPLAY 0.617021 (2085 4585);
PAINT ORANGE (2085 4585);
FORCEPROP 2 LASTPIN (2075 4525) $PN 110
J 0
(2085 4535);
DISPLAY 0.617021 (2085 4535);
PAINT ORANGE (2085 4535);
FORCEPROP 2 LASTPIN (2075 4425) $PN 99
J 0
(2085 4435);
DISPLAY 0.617021 (2085 4435);
PAINT ORANGE (2085 4435);
FORCEPROP 2 LASTPIN (2075 4375) $PN 100
J 0
(2085 4385);
DISPLAY 0.617021 (2085 4385);
PAINT ORANGE (2085 4385);
FORCEPROP 2 LASTPIN (2075 4325) $PN 40
J 0
(2085 4335);
DISPLAY 0.617021 (2085 4335);
PAINT ORANGE (2085 4335);
FORCEPROP 2 LASTPIN (2075 4275) $PN 41
J 0
(2085 4285);
DISPLAY 0.617021 (2085 4285);
PAINT ORANGE (2085 4285);
FORCEPROP 2 LASTPIN (2075 4225) $PN 29
J 0
(2085 4235);
DISPLAY 0.617021 (2085 4235);
PAINT ORANGE (2085 4235);
FORCEPROP 2 LASTPIN (2075 4125) $PN 18
J 0
(2085 4135);
DISPLAY 0.617021 (2085 4135);
PAINT ORANGE (2085 4135);
FORCEPROP 2 LASTPIN (2075 4075) $PN 19
J 0
(2085 4085);
DISPLAY 0.617021 (2085 4085);
PAINT ORANGE (2085 4085);
FORCEPROP 2 LASTPIN (2075 4025) $PN 7
J 0
(2085 4035);
DISPLAY 0.617021 (2085 4035);
PAINT ORANGE (2085 4035);
FORCEPROP 2 LASTPIN (2075 3975) $PN 8
J 0
(2085 3985);
DISPLAY 0.617021 (2085 3985);
PAINT ORANGE (2085 3985);
FORCEPROP 2 LASTPIN (2075 3925) $PN 197
J 0
(2085 3935);
DISPLAY 0.617021 (2085 3935);
PAINT ORANGE (2085 3935);
FORCEPROP 2 LASTPIN (2075 3875) $PN 196
J 0
(2085 3885);
DISPLAY 0.617021 (2085 3885);
PAINT ORANGE (2085 3885);
FORCEPROP 2 LASTPIN (2075 3825) $PN 278
J 0
(2085 3835);
DISPLAY 0.617021 (2085 3835);
PAINT ORANGE (2085 3835);
FORCEPROP 2 LASTPIN (2075 3725) $PN 267
J 0
(2085 3735);
DISPLAY 0.617021 (2085 3735);
PAINT ORANGE (2085 3735);
FORCEPROP 2 LASTPIN (2075 3675) $PN 266
J 0
(2085 3685);
DISPLAY 0.617021 (2085 3685);
PAINT ORANGE (2085 3685);
FORCEPROP 2 LASTPIN (2075 3625) $PN 256
J 0
(2085 3635);
DISPLAY 0.617021 (2085 3635);
PAINT ORANGE (2085 3635);
FORCEPROP 2 LASTPIN (2075 3575) $PN 255
J 0
(2085 3585);
DISPLAY 0.617021 (2085 3585);
PAINT ORANGE (2085 3585);
FORCEPROP 2 LASTPIN (2075 3525) $PN 245
J 0
(2085 3535);
DISPLAY 0.617021 (2085 3535);
PAINT ORANGE (2085 3535);
FORCEPROP 2 LASTPIN (2075 3475) $PN 244
J 0
(2085 3485);
DISPLAY 0.617021 (2085 3485);
PAINT ORANGE (2085 3485);
FORCEPROP 2 LASTPIN (2075 3425) $PN 186
J 0
(2085 3435);
DISPLAY 0.617021 (2085 3435);
PAINT ORANGE (2085 3435);
FORCEPROP 2 LASTPIN (2075 3375) $PN 185
J 0
(2085 3385);
DISPLAY 0.617021 (2085 3385);
PAINT ORANGE (2085 3385);
FORCEPROP 2 LASTPIN (2075 3325) $PN 175
J 0
(2085 3335);
DISPLAY 0.617021 (2085 3335);
PAINT ORANGE (2085 3335);
FORCEPROP 2 LASTPIN (2075 3275) $PN 174
J 0
(2085 3285);
DISPLAY 0.617021 (2085 3285);
PAINT ORANGE (2085 3285);
FORCEPROP 2 LASTPIN (2075 3075) $PN 152
J 0
(2085 3085);
DISPLAY 0.617021 (2085 3085);
PAINT ORANGE (2085 3085);
FORCEPROP 2 LASTPIN (2075 3775) $PN 277
J 0
(2085 3785);
DISPLAY 0.617021 (2085 3785);
PAINT ORANGE (2085 3785);
FORCEPROP 2 LASTPIN (2075 4175) $PN 30
J 0
(2085 4185);
DISPLAY 0.617021 (2085 4185);
PAINT ORANGE (2085 4185);
FORCEPROP 1 LAST LOCATION J9L2
J 0
(1225 5075);
DISPLAY 0.617021 (1225 5075);
PAINT AQUA (1225 5075);
FORCEPROP 0 LAST BOM_SS NOPOP
J 0
(1431 5049);
DISPLAY 1.021277 (1431 5049);
PAINT BROWN (1431 5049);
DISPLAY BOTH (1431 5049);
FORCEPROP 2 LASTPIN (2075 3125) $PN 153
J 0
(2085 3135);
DISPLAY 0.617021 (2085 3135);
PAINT ORANGE (2085 3135);
FORCEPROP 2 LASTPIN (2075 3175) $PN 163
J 0
(2085 3185);
DISPLAY 0.617021 (2085 3185);
PAINT ORANGE (2085 3185);
FORCEPROP 2 LASTPIN (2075 3225) $PN 164
J 0
(2085 3235);
DISPLAY 0.617021 (2085 3235);
PAINT ORANGE (2085 3235);
FORCEPROP 2 LASTPIN (2075 4475) $PN 111
J 0
(2085 4485);
DISPLAY 0.617021 (2085 4485);
PAINT ORANGE (2085 4485);
FORCEPROP 1 LAST PACK_TYPE PIP
J 0
(1225 5125);
PAINT SKYBLUE (1225 5125);
DISPLAY INVISIBLE (1225 5125);
FORCEPROP 2 LAST BOM_COST MEM
J 0
(1625 3975);
PAINT ORANGE (1625 3975);
DISPLAY INVISIBLE (1625 3975);
FORCEPROP 2 LAST CDS_LIB mstr_sconn
J 0
(1625 3975);
PAINT ORANGE (1625 3975);
DISPLAY INVISIBLE (1625 3975);
FORCEPROP 2 LAST SEC_TYPE PIP
J 0
(1225 5125);
DISPLAY 1.021277 (1225 5125);
PAINT ORANGE (1225 5125);
DISPLAY INVISIBLE (1225 5125);
FORCEPROP 2 LAST SEC 2
J 0
(1225 5125);
DISPLAY 0.680851 (1225 5125);
PAINT MONO (1225 5125);
DISPLAY INVISIBLE (1225 5125);
FORCEPROP 2 LAST CDS_LOCATION J9L2
J 0
(1225 5075);
DISPLAY 0.617021 (1225 5075);
PAINT AQUA (1225 5075);
DISPLAY INVISIBLE (1225 5075);
FORCEPROP 1 LAST PATH I100
J 0
(1625 5025);
PAINT GREEN (1625 5025);
DISPLAY INVISIBLE (1625 5025);
FORCEPROP 2 LAST ROOM DDR4_CH_L
J 0
(1225 5175);
PAINT ORANGE (1225 5175);
DISPLAY INVISIBLE (1225 5175);
FORCEADD OFFPAGE..1
(-2225 4625);
FORCEPROP 2 LAST $XR1 85 
J 0
(-2566 4625);
DISPLAY 0.638298 (-2566 4625);
PAINT MONO (-2566 4625);
FORCEPROP 2 LAST $XR0 61 
J 0
(-2476 4625);
DISPLAY 0.638298 (-2476 4625);
PAINT MONO (-2476 4625);
FORCEPROP 2 LAST CDS_LIB mstr_standard
J 0
(-2225 4625);
DISPLAY 0.787234 (-2225 4625);
PAINT MONO (-2225 4625);
DISPLAY INVISIBLE (-2225 4625);
FORCEPROP 1 LAST OFFPAGE TRUE
J 0
(-1900 4500);
DISPLAY 0.936170 (-1900 4500);
PAINT GREEN (-1900 4500);
DISPLAY INVISIBLE (-1900 4500);
FORCEPROP 1 LAST COMMENT_BODY TRUE
J 0
(-2100 4525);
DISPLAY 0.936170 (-2100 4525);
PAINT GREEN (-2100 4525);
DISPLAY INVISIBLE (-2100 4525);
FORCEPROP 2 LAST PATH I101
J 0
(-2475 4675);
DISPLAY 1.021277 (-2475 4675);
PAINT ORANGE (-2475 4675);
DISPLAY INVISIBLE (-2475 4675);
FORCEADD TAP..6
(-1625 3775);
FORCEPROP 3 LASTPIN (-1575 3775) SIG_NAME M_L_MA<1>
J 0
(-1565 3785);
DISPLAY 0.659574 (-1565 3785);
PAINT MONO (-1565 3785);
DISPLAY INVISIBLE (-1565 3785);
FORCEPROP 1 LASTPIN (-1575 3775) BN 1
J 0
(-1625 3785);
DISPLAY 0.617021 (-1625 3785);
PAINT PINK (-1625 3785);
FORCEPROP 2 LAST CDS_LIB mstr_standard
J 2
(-1625 3775);
DISPLAY 0.787234 (-1625 3775);
PAINT MONO (-1625 3775);
DISPLAY INVISIBLE (-1625 3775);
FORCEPROP 1 LAST BODY_TYPE PLUMBING
J 0
(-1625 3725);
DISPLAY 1.234043 (-1625 3725);
PAINT GREEN (-1625 3725);
DISPLAY INVISIBLE (-1625 3725);
FORCEPROP 1 LAST HDL_TAP TRUE
J 0
(-1300 3650);
DISPLAY 1.234043 (-1300 3650);
PAINT GREEN (-1300 3650);
DISPLAY INVISIBLE (-1300 3650);
FORCEPROP 1 LAST PATH I102
J 0
(-1627 3775);
DISPLAY 0.872340 (-1627 3775);
PAINT GREEN (-1627 3775);
DISPLAY INVISIBLE (-1627 3775);
FORCEADD TAP..6
(-1625 3825);
FORCEPROP 3 LASTPIN (-1575 3825) SIG_NAME M_L_MA<2>
J 0
(-1565 3835);
DISPLAY 0.659574 (-1565 3835);
PAINT MONO (-1565 3835);
DISPLAY INVISIBLE (-1565 3835);
FORCEPROP 1 LASTPIN (-1575 3825) BN 2
J 0
(-1625 3835);
DISPLAY 0.617021 (-1625 3835);
PAINT PINK (-1625 3835);
FORCEPROP 2 LAST CDS_LIB mstr_standard
J 2
(-1625 3825);
DISPLAY 0.787234 (-1625 3825);
PAINT MONO (-1625 3825);
DISPLAY INVISIBLE (-1625 3825);
FORCEPROP 1 LAST BODY_TYPE PLUMBING
J 0
(-1625 3775);
DISPLAY 1.234043 (-1625 3775);
PAINT GREEN (-1625 3775);
DISPLAY INVISIBLE (-1625 3775);
FORCEPROP 1 LAST HDL_TAP TRUE
J 0
(-1300 3700);
DISPLAY 1.234043 (-1300 3700);
PAINT GREEN (-1300 3700);
DISPLAY INVISIBLE (-1300 3700);
FORCEPROP 1 LAST PATH I103
J 0
(-1627 3825);
DISPLAY 0.872340 (-1627 3825);
PAINT GREEN (-1627 3825);
DISPLAY INVISIBLE (-1627 3825);
FORCEADD TAP..6
(-1625 3875);
FORCEPROP 3 LASTPIN (-1575 3875) SIG_NAME M_L_MA<3>
J 0
(-1565 3885);
DISPLAY 0.659574 (-1565 3885);
PAINT MONO (-1565 3885);
DISPLAY INVISIBLE (-1565 3885);
FORCEPROP 1 LASTPIN (-1575 3875) BN 3
J 0
(-1625 3885);
DISPLAY 0.617021 (-1625 3885);
PAINT PINK (-1625 3885);
FORCEPROP 2 LAST CDS_LIB mstr_standard
J 2
(-1625 3875);
DISPLAY 0.787234 (-1625 3875);
PAINT MONO (-1625 3875);
DISPLAY INVISIBLE (-1625 3875);
FORCEPROP 1 LAST BODY_TYPE PLUMBING
J 0
(-1625 3825);
DISPLAY 1.234043 (-1625 3825);
PAINT GREEN (-1625 3825);
DISPLAY INVISIBLE (-1625 3825);
FORCEPROP 1 LAST HDL_TAP TRUE
J 0
(-1300 3750);
DISPLAY 1.234043 (-1300 3750);
PAINT GREEN (-1300 3750);
DISPLAY INVISIBLE (-1300 3750);
FORCEPROP 1 LAST PATH I104
J 0
(-1627 3875);
DISPLAY 0.872340 (-1627 3875);
PAINT GREEN (-1627 3875);
DISPLAY INVISIBLE (-1627 3875);
FORCEADD TAP..6
(-1625 3975);
FORCEPROP 3 LASTPIN (-1575 3975) SIG_NAME M_L_MA<5>
J 0
(-1565 3985);
DISPLAY 0.659574 (-1565 3985);
PAINT MONO (-1565 3985);
DISPLAY INVISIBLE (-1565 3985);
FORCEPROP 1 LASTPIN (-1575 3975) BN 5
J 0
(-1625 3985);
DISPLAY 0.617021 (-1625 3985);
PAINT PINK (-1625 3985);
FORCEPROP 2 LAST CDS_LIB mstr_standard
J 2
(-1625 3975);
DISPLAY 0.787234 (-1625 3975);
PAINT MONO (-1625 3975);
DISPLAY INVISIBLE (-1625 3975);
FORCEPROP 1 LAST BODY_TYPE PLUMBING
J 0
(-1625 3925);
DISPLAY 1.234043 (-1625 3925);
PAINT GREEN (-1625 3925);
DISPLAY INVISIBLE (-1625 3925);
FORCEPROP 1 LAST HDL_TAP TRUE
J 0
(-1300 3850);
DISPLAY 1.234043 (-1300 3850);
PAINT GREEN (-1300 3850);
DISPLAY INVISIBLE (-1300 3850);
FORCEPROP 1 LAST PATH I105
J 0
(-1627 3975);
DISPLAY 0.872340 (-1627 3975);
PAINT GREEN (-1627 3975);
DISPLAY INVISIBLE (-1627 3975);
FORCEADD TAP..6
(-1625 3925);
FORCEPROP 3 LASTPIN (-1575 3925) SIG_NAME M_L_MA<4>
J 0
(-1565 3935);
DISPLAY 0.659574 (-1565 3935);
PAINT MONO (-1565 3935);
DISPLAY INVISIBLE (-1565 3935);
FORCEPROP 1 LASTPIN (-1575 3925) BN 4
J 0
(-1625 3935);
DISPLAY 0.617021 (-1625 3935);
PAINT PINK (-1625 3935);
FORCEPROP 2 LAST CDS_LIB mstr_standard
J 2
(-1625 3925);
DISPLAY 0.787234 (-1625 3925);
PAINT MONO (-1625 3925);
DISPLAY INVISIBLE (-1625 3925);
FORCEPROP 1 LAST BODY_TYPE PLUMBING
J 0
(-1625 3875);
DISPLAY 1.234043 (-1625 3875);
PAINT GREEN (-1625 3875);
DISPLAY INVISIBLE (-1625 3875);
FORCEPROP 1 LAST HDL_TAP TRUE
J 0
(-1300 3800);
DISPLAY 1.234043 (-1300 3800);
PAINT GREEN (-1300 3800);
DISPLAY INVISIBLE (-1300 3800);
FORCEPROP 1 LAST PATH I106
J 0
(-1627 3925);
DISPLAY 0.872340 (-1627 3925);
PAINT GREEN (-1627 3925);
DISPLAY INVISIBLE (-1627 3925);
FORCEADD TAP..6
(-1625 4025);
FORCEPROP 3 LASTPIN (-1575 4025) SIG_NAME M_L_MA<6>
J 0
(-1565 4035);
DISPLAY 0.659574 (-1565 4035);
PAINT MONO (-1565 4035);
DISPLAY INVISIBLE (-1565 4035);
FORCEPROP 1 LASTPIN (-1575 4025) BN 6
J 0
(-1625 4035);
DISPLAY 0.617021 (-1625 4035);
PAINT PINK (-1625 4035);
FORCEPROP 2 LAST CDS_LIB mstr_standard
J 2
(-1625 4025);
DISPLAY 0.787234 (-1625 4025);
PAINT MONO (-1625 4025);
DISPLAY INVISIBLE (-1625 4025);
FORCEPROP 1 LAST BODY_TYPE PLUMBING
J 0
(-1625 3975);
DISPLAY 1.234043 (-1625 3975);
PAINT GREEN (-1625 3975);
DISPLAY INVISIBLE (-1625 3975);
FORCEPROP 1 LAST HDL_TAP TRUE
J 0
(-1300 3900);
DISPLAY 1.234043 (-1300 3900);
PAINT GREEN (-1300 3900);
DISPLAY INVISIBLE (-1300 3900);
FORCEPROP 1 LAST PATH I107
J 0
(-1627 4025);
DISPLAY 0.872340 (-1627 4025);
PAINT GREEN (-1627 4025);
DISPLAY INVISIBLE (-1627 4025);
FORCEADD TAP..6
(-1625 4125);
FORCEPROP 3 LASTPIN (-1575 4125) SIG_NAME M_L_MA<8>
J 0
(-1565 4135);
DISPLAY 0.659574 (-1565 4135);
PAINT MONO (-1565 4135);
DISPLAY INVISIBLE (-1565 4135);
FORCEPROP 1 LASTPIN (-1575 4125) BN 8
J 0
(-1625 4135);
DISPLAY 0.617021 (-1625 4135);
PAINT PINK (-1625 4135);
FORCEPROP 2 LAST CDS_LIB mstr_standard
J 2
(-1625 4125);
DISPLAY 0.787234 (-1625 4125);
PAINT MONO (-1625 4125);
DISPLAY INVISIBLE (-1625 4125);
FORCEPROP 1 LAST BODY_TYPE PLUMBING
J 0
(-1625 4075);
DISPLAY 1.234043 (-1625 4075);
PAINT GREEN (-1625 4075);
DISPLAY INVISIBLE (-1625 4075);
FORCEPROP 1 LAST HDL_TAP TRUE
J 0
(-1300 4000);
DISPLAY 1.234043 (-1300 4000);
PAINT GREEN (-1300 4000);
DISPLAY INVISIBLE (-1300 4000);
FORCEPROP 1 LAST PATH I108
J 0
(-1627 4125);
DISPLAY 0.872340 (-1627 4125);
PAINT GREEN (-1627 4125);
DISPLAY INVISIBLE (-1627 4125);
FORCEADD TAP..6
(-1625 4075);
FORCEPROP 3 LASTPIN (-1575 4075) SIG_NAME M_L_MA<7>
J 0
(-1565 4085);
DISPLAY 0.659574 (-1565 4085);
PAINT MONO (-1565 4085);
DISPLAY INVISIBLE (-1565 4085);
FORCEPROP 1 LASTPIN (-1575 4075) BN 7
J 0
(-1625 4085);
DISPLAY 0.617021 (-1625 4085);
PAINT PINK (-1625 4085);
FORCEPROP 2 LAST CDS_LIB mstr_standard
J 2
(-1625 4075);
DISPLAY 0.787234 (-1625 4075);
PAINT MONO (-1625 4075);
DISPLAY INVISIBLE (-1625 4075);
FORCEPROP 1 LAST BODY_TYPE PLUMBING
J 0
(-1625 4025);
DISPLAY 1.234043 (-1625 4025);
PAINT GREEN (-1625 4025);
DISPLAY INVISIBLE (-1625 4025);
FORCEPROP 1 LAST HDL_TAP TRUE
J 0
(-1300 3950);
DISPLAY 1.234043 (-1300 3950);
PAINT GREEN (-1300 3950);
DISPLAY INVISIBLE (-1300 3950);
FORCEPROP 1 LAST PATH I109
J 0
(-1627 4075);
DISPLAY 0.872340 (-1627 4075);
PAINT GREEN (-1627 4075);
DISPLAY INVISIBLE (-1627 4075);
FORCEADD OFFPAGE..6
(-2225 1575);
FORCEPROP 2 LASTPIN (-2175 1575) SIG_NAME SMB_DDR_KLM_VPP_SDA
J 0
(-2135 1585);
DISPLAY 0.617021 (-2135 1585);
PAINT ORANGE (-2135 1585);
FORCEPROP 2 LAST $XR5 99 
J 0
(-2924 1575);
DISPLAY 0.638298 (-2924 1575);
PAINT MONO (-2924 1575);
FORCEPROP 2 LAST $XR4 88 
J 0
(-2834 1575);
DISPLAY 0.638298 (-2834 1575);
PAINT MONO (-2834 1575);
FORCEPROP 2 LAST $XR3 87 
J 0
(-2744 1575);
DISPLAY 0.638298 (-2744 1575);
PAINT MONO (-2744 1575);
FORCEPROP 2 LAST $XR2 85 
J 0
(-2654 1575);
DISPLAY 0.638298 (-2654 1575);
PAINT MONO (-2654 1575);
FORCEPROP 2 LAST $XR1 84 
J 0
(-2564 1575);
DISPLAY 0.638298 (-2564 1575);
PAINT MONO (-2564 1575);
FORCEPROP 2 LAST $XR0 83 
J 0
(-2474 1575);
DISPLAY 0.638298 (-2474 1575);
PAINT MONO (-2474 1575);
FORCEPROP 2 LAST CDS_LIB mstr_standard
J 0
(-2225 1575);
DISPLAY 0.787234 (-2225 1575);
PAINT MONO (-2225 1575);
DISPLAY INVISIBLE (-2225 1575);
FORCEPROP 1 LAST OFFPAGE TRUE
J 0
(-1900 1450);
DISPLAY 0.936170 (-1900 1450);
PAINT GREEN (-1900 1450);
DISPLAY INVISIBLE (-1900 1450);
FORCEPROP 1 LAST COMMENT_BODY TRUE
J 0
(-2125 1500);
DISPLAY 0.936170 (-2125 1500);
PAINT GREEN (-2125 1500);
DISPLAY INVISIBLE (-2125 1500);
FORCEPROP 2 LAST PATH I11
J 0
(-2450 1625);
DISPLAY 1.021277 (-2450 1625);
PAINT ORANGE (-2450 1625);
DISPLAY INVISIBLE (-2450 1625);
FORCEADD TAP..6
(-1625 4175);
FORCEPROP 3 LASTPIN (-1575 4175) SIG_NAME M_L_MA<9>
J 0
(-1565 4185);
DISPLAY 0.659574 (-1565 4185);
PAINT MONO (-1565 4185);
DISPLAY INVISIBLE (-1565 4185);
FORCEPROP 1 LASTPIN (-1575 4175) BN 9
J 0
(-1625 4185);
DISPLAY 0.617021 (-1625 4185);
PAINT PINK (-1625 4185);
FORCEPROP 2 LAST CDS_LIB mstr_standard
J 2
(-1625 4175);
DISPLAY 0.787234 (-1625 4175);
PAINT MONO (-1625 4175);
DISPLAY INVISIBLE (-1625 4175);
FORCEPROP 1 LAST BODY_TYPE PLUMBING
J 0
(-1625 4125);
DISPLAY 1.234043 (-1625 4125);
PAINT GREEN (-1625 4125);
DISPLAY INVISIBLE (-1625 4125);
FORCEPROP 1 LAST HDL_TAP TRUE
J 0
(-1300 4050);
DISPLAY 1.234043 (-1300 4050);
PAINT GREEN (-1300 4050);
DISPLAY INVISIBLE (-1300 4050);
FORCEPROP 1 LAST PATH I110
J 0
(-1627 4175);
DISPLAY 0.872340 (-1627 4175);
PAINT GREEN (-1627 4175);
DISPLAY INVISIBLE (-1627 4175);
FORCEADD TAP..6
(-1625 4225);
FORCEPROP 3 LASTPIN (-1575 4225) SIG_NAME M_L_MA<10>
J 0
(-1565 4235);
DISPLAY 0.659574 (-1565 4235);
PAINT MONO (-1565 4235);
DISPLAY INVISIBLE (-1565 4235);
FORCEPROP 1 LASTPIN (-1575 4225) BN 10
J 0
(-1625 4235);
DISPLAY 0.617021 (-1625 4235);
PAINT PINK (-1625 4235);
FORCEPROP 2 LAST CDS_LIB mstr_standard
J 2
(-1625 4225);
DISPLAY 0.787234 (-1625 4225);
PAINT MONO (-1625 4225);
DISPLAY INVISIBLE (-1625 4225);
FORCEPROP 1 LAST BODY_TYPE PLUMBING
J 0
(-1625 4175);
DISPLAY 1.234043 (-1625 4175);
PAINT GREEN (-1625 4175);
DISPLAY INVISIBLE (-1625 4175);
FORCEPROP 1 LAST HDL_TAP TRUE
J 0
(-1300 4100);
DISPLAY 1.234043 (-1300 4100);
PAINT GREEN (-1300 4100);
DISPLAY INVISIBLE (-1300 4100);
FORCEPROP 1 LAST PATH I111
J 0
(-1627 4225);
DISPLAY 0.872340 (-1627 4225);
PAINT GREEN (-1627 4225);
DISPLAY INVISIBLE (-1627 4225);
FORCEADD TAP..6
(-1625 4275);
FORCEPROP 3 LASTPIN (-1575 4275) SIG_NAME M_L_MA<11>
J 0
(-1565 4285);
DISPLAY 0.659574 (-1565 4285);
PAINT MONO (-1565 4285);
DISPLAY INVISIBLE (-1565 4285);
FORCEPROP 1 LASTPIN (-1575 4275) BN 11
J 0
(-1625 4285);
DISPLAY 0.617021 (-1625 4285);
PAINT PINK (-1625 4285);
FORCEPROP 2 LAST CDS_LIB mstr_standard
J 2
(-1625 4275);
DISPLAY 0.787234 (-1625 4275);
PAINT MONO (-1625 4275);
DISPLAY INVISIBLE (-1625 4275);
FORCEPROP 1 LAST BODY_TYPE PLUMBING
J 0
(-1625 4225);
DISPLAY 1.234043 (-1625 4225);
PAINT GREEN (-1625 4225);
DISPLAY INVISIBLE (-1625 4225);
FORCEPROP 1 LAST HDL_TAP TRUE
J 0
(-1300 4150);
DISPLAY 1.234043 (-1300 4150);
PAINT GREEN (-1300 4150);
DISPLAY INVISIBLE (-1300 4150);
FORCEPROP 1 LAST PATH I112
J 0
(-1627 4275);
DISPLAY 0.872340 (-1627 4275);
PAINT GREEN (-1627 4275);
DISPLAY INVISIBLE (-1627 4275);
FORCEADD TAP..6
(-1625 4375);
FORCEPROP 3 LASTPIN (-1575 4375) SIG_NAME M_L_MA<13>
J 0
(-1565 4385);
DISPLAY 0.659574 (-1565 4385);
PAINT MONO (-1565 4385);
DISPLAY INVISIBLE (-1565 4385);
FORCEPROP 1 LASTPIN (-1575 4375) BN 13
J 0
(-1625 4385);
DISPLAY 0.617021 (-1625 4385);
PAINT PINK (-1625 4385);
FORCEPROP 2 LAST CDS_LIB mstr_standard
J 2
(-1625 4375);
DISPLAY 0.787234 (-1625 4375);
PAINT MONO (-1625 4375);
DISPLAY INVISIBLE (-1625 4375);
FORCEPROP 1 LAST BODY_TYPE PLUMBING
J 0
(-1625 4325);
DISPLAY 1.234043 (-1625 4325);
PAINT GREEN (-1625 4325);
DISPLAY INVISIBLE (-1625 4325);
FORCEPROP 1 LAST HDL_TAP TRUE
J 0
(-1300 4250);
DISPLAY 1.234043 (-1300 4250);
PAINT GREEN (-1300 4250);
DISPLAY INVISIBLE (-1300 4250);
FORCEPROP 1 LAST PATH I113
J 0
(-1627 4375);
DISPLAY 0.872340 (-1627 4375);
PAINT GREEN (-1627 4375);
DISPLAY INVISIBLE (-1627 4375);
FORCEADD TAP..6
(-1625 4325);
FORCEPROP 3 LASTPIN (-1575 4325) SIG_NAME M_L_MA<12>
J 0
(-1565 4335);
DISPLAY 0.659574 (-1565 4335);
PAINT MONO (-1565 4335);
DISPLAY INVISIBLE (-1565 4335);
FORCEPROP 1 LASTPIN (-1575 4325) BN 12
J 0
(-1625 4335);
DISPLAY 0.617021 (-1625 4335);
PAINT PINK (-1625 4335);
FORCEPROP 2 LAST CDS_LIB mstr_standard
J 2
(-1625 4325);
DISPLAY 0.787234 (-1625 4325);
PAINT MONO (-1625 4325);
DISPLAY INVISIBLE (-1625 4325);
FORCEPROP 1 LAST BODY_TYPE PLUMBING
J 0
(-1625 4275);
DISPLAY 1.234043 (-1625 4275);
PAINT GREEN (-1625 4275);
DISPLAY INVISIBLE (-1625 4275);
FORCEPROP 1 LAST HDL_TAP TRUE
J 0
(-1300 4200);
DISPLAY 1.234043 (-1300 4200);
PAINT GREEN (-1300 4200);
DISPLAY INVISIBLE (-1300 4200);
FORCEPROP 1 LAST PATH I114
J 0
(-1627 4325);
DISPLAY 0.872340 (-1627 4325);
PAINT GREEN (-1627 4325);
DISPLAY INVISIBLE (-1627 4325);
FORCEADD TAP..6
(-1625 4425);
FORCEPROP 3 LASTPIN (-1575 4425) SIG_NAME M_L_MA<14>
J 0
(-1565 4435);
DISPLAY 0.659574 (-1565 4435);
PAINT MONO (-1565 4435);
DISPLAY INVISIBLE (-1565 4435);
FORCEPROP 1 LASTPIN (-1575 4425) BN 14
J 0
(-1625 4435);
DISPLAY 0.617021 (-1625 4435);
PAINT PINK (-1625 4435);
FORCEPROP 2 LAST CDS_LIB mstr_standard
J 2
(-1625 4425);
DISPLAY 0.787234 (-1625 4425);
PAINT MONO (-1625 4425);
DISPLAY INVISIBLE (-1625 4425);
FORCEPROP 1 LAST BODY_TYPE PLUMBING
J 0
(-1625 4375);
DISPLAY 1.234043 (-1625 4375);
PAINT GREEN (-1625 4375);
DISPLAY INVISIBLE (-1625 4375);
FORCEPROP 1 LAST HDL_TAP TRUE
J 0
(-1300 4300);
DISPLAY 1.234043 (-1300 4300);
PAINT GREEN (-1300 4300);
DISPLAY INVISIBLE (-1300 4300);
FORCEPROP 1 LAST PATH I115
J 0
(-1627 4425);
DISPLAY 0.872340 (-1627 4425);
PAINT GREEN (-1627 4425);
DISPLAY INVISIBLE (-1627 4425);
FORCEADD TAP..6
(-1625 4475);
FORCEPROP 3 LASTPIN (-1575 4475) SIG_NAME M_L_MA<15>
J 0
(-1565 4485);
DISPLAY 0.659574 (-1565 4485);
PAINT MONO (-1565 4485);
DISPLAY INVISIBLE (-1565 4485);
FORCEPROP 1 LASTPIN (-1575 4475) BN 15
J 0
(-1625 4485);
DISPLAY 0.617021 (-1625 4485);
PAINT PINK (-1625 4485);
FORCEPROP 2 LAST CDS_LIB mstr_standard
J 2
(-1625 4475);
DISPLAY 0.787234 (-1625 4475);
PAINT MONO (-1625 4475);
DISPLAY INVISIBLE (-1625 4475);
FORCEPROP 1 LAST BODY_TYPE PLUMBING
J 0
(-1625 4425);
DISPLAY 1.234043 (-1625 4425);
PAINT GREEN (-1625 4425);
DISPLAY INVISIBLE (-1625 4425);
FORCEPROP 1 LAST HDL_TAP TRUE
J 0
(-1300 4350);
DISPLAY 1.234043 (-1300 4350);
PAINT GREEN (-1300 4350);
DISPLAY INVISIBLE (-1300 4350);
FORCEPROP 1 LAST PATH I116
J 0
(-1627 4475);
DISPLAY 0.872340 (-1627 4475);
PAINT GREEN (-1627 4475);
DISPLAY INVISIBLE (-1627 4475);
FORCEADD TAP..6
(-1625 4525);
FORCEPROP 3 LASTPIN (-1575 4525) SIG_NAME M_L_MA<16>
J 0
(-1565 4535);
DISPLAY 0.659574 (-1565 4535);
PAINT MONO (-1565 4535);
DISPLAY INVISIBLE (-1565 4535);
FORCEPROP 1 LASTPIN (-1575 4525) BN 16
J 0
(-1625 4535);
DISPLAY 0.617021 (-1625 4535);
PAINT PINK (-1625 4535);
FORCEPROP 2 LAST CDS_LIB mstr_standard
J 2
(-1625 4525);
DISPLAY 0.787234 (-1625 4525);
PAINT MONO (-1625 4525);
DISPLAY INVISIBLE (-1625 4525);
FORCEPROP 1 LAST BODY_TYPE PLUMBING
J 0
(-1625 4475);
DISPLAY 1.234043 (-1625 4475);
PAINT GREEN (-1625 4475);
DISPLAY INVISIBLE (-1625 4475);
FORCEPROP 1 LAST HDL_TAP TRUE
J 0
(-1300 4400);
DISPLAY 1.234043 (-1300 4400);
PAINT GREEN (-1300 4400);
DISPLAY INVISIBLE (-1300 4400);
FORCEPROP 1 LAST PATH I117
J 0
(-1627 4525);
DISPLAY 0.872340 (-1627 4525);
PAINT GREEN (-1627 4525);
DISPLAY INVISIBLE (-1627 4525);
FORCEADD TAP..6
(-1625 4575);
FORCEPROP 3 LASTPIN (-1575 4575) SIG_NAME M_L_MA<17>
J 0
(-1565 4585);
DISPLAY 0.659574 (-1565 4585);
PAINT MONO (-1565 4585);
DISPLAY INVISIBLE (-1565 4585);
FORCEPROP 1 LASTPIN (-1575 4575) BN 17
J 0
(-1625 4585);
DISPLAY 0.617021 (-1625 4585);
PAINT PINK (-1625 4585);
FORCEPROP 2 LAST CDS_LIB mstr_standard
J 0
(-1625 4575);
DISPLAY 0.787234 (-1625 4575);
PAINT MONO (-1625 4575);
DISPLAY INVISIBLE (-1625 4575);
FORCEPROP 1 LAST BODY_TYPE PLUMBING
J 0
(-1625 4525);
DISPLAY 1.234043 (-1625 4525);
PAINT GREEN (-1625 4525);
DISPLAY INVISIBLE (-1625 4525);
FORCEPROP 1 LAST HDL_TAP TRUE
J 0
(-1300 4450);
DISPLAY 1.234043 (-1300 4450);
PAINT GREEN (-1300 4450);
DISPLAY INVISIBLE (-1300 4450);
FORCEPROP 1 LAST PATH I118
J 0
(-1627 4575);
DISPLAY 0.872340 (-1627 4575);
PAINT GREEN (-1627 4575);
DISPLAY INVISIBLE (-1627 4575);
FORCEADD TAP..6
R 2
(-125 3925);
FORCEPROP 3 LASTPIN (-175 3925) SIG_NAME M_L_DQ<50>
J 0
(-165 3935);
DISPLAY 0.659574 (-165 3935);
PAINT MONO (-165 3935);
DISPLAY INVISIBLE (-165 3935);
FORCEPROP 1 LASTPIN (-175 3925) BN 50
J 2
(-125 3935);
DISPLAY 0.617021 (-125 3935);
PAINT PINK (-125 3935);
FORCEPROP 2 LAST CDS_LIB mstr_standard
J 2
(-125 3925);
DISPLAY 0.787234 (-125 3925);
PAINT MONO (-125 3925);
DISPLAY INVISIBLE (-125 3925);
FORCEPROP 1 LAST BODY_TYPE PLUMBING
J 2
(-125 3875);
DISPLAY 1.234043 (-125 3875);
PAINT GREEN (-125 3875);
DISPLAY INVISIBLE (-125 3875);
FORCEPROP 1 LAST HDL_TAP TRUE
J 2
(-450 3800);
DISPLAY 1.234043 (-450 3800);
PAINT GREEN (-450 3800);
DISPLAY INVISIBLE (-450 3800);
FORCEPROP 1 LAST PATH I119
J 2
(-123 3925);
DISPLAY 0.872340 (-123 3925);
PAINT GREEN (-123 3925);
DISPLAY INVISIBLE (-123 3925);
FORCEADD SCONN288_H44441003..1
(-875 2925);
FORCEPROP 2 LASTPIN (-1375 4575) $PN 234
J 2
(-1385 4585);
DISPLAY 0.617021 (-1385 4585);
PAINT ORANGE (-1385 4585);
FORCEPROP 1 LAST LOCATION J9L2
J 0
(-1325 4825);
DISPLAY 0.617021 (-1325 4825);
PAINT AQUA (-1325 4825);
FORCEPROP 1 LAST PART_NUMBER H44441-003
J 0
(-1325 925);
DISPLAY 0.617021 (-1325 925);
PAINT BLUE (-1325 925);
FORCEPROP 1 LAST MATERIAL SCONN
J 0
(-1325 4775);
DISPLAY 0.617021 (-1325 4775);
PAINT SKYBLUE (-1325 4775);
FORCEPROP 2 LASTPIN (-1375 1425) $PN 146
J 2
(-1385 1435);
DISPLAY 0.617021 (-1385 1435);
PAINT ORANGE (-1385 1435);
FORCEPROP 2 LASTPIN (-1375 1775) $PN 284
J 2
(-1385 1785);
DISPLAY 0.617021 (-1385 1785);
PAINT ORANGE (-1385 1785);
FORCEPROP 2 LASTPIN (-1375 1575) $PN 285
J 2
(-1385 1585);
DISPLAY 0.617021 (-1385 1585);
PAINT ORANGE (-1385 1585);
FORCEPROP 2 LASTPIN (-1375 1525) $PN 141
J 2
(-1385 1535);
DISPLAY 0.617021 (-1385 1535);
PAINT ORANGE (-1385 1535);
FORCEPROP 2 LASTPIN (-1375 1125) $PN 230
J 2
(-1385 1135);
DISPLAY 0.617021 (-1385 1135);
PAINT ORANGE (-1385 1135);
FORCEPROP 2 LASTPIN (-1375 1725) $PN 238
J 2
(-1385 1735);
DISPLAY 0.617021 (-1385 1735);
PAINT ORANGE (-1385 1735);
FORCEPROP 2 LASTPIN (-1375 1675) $PN 140
J 2
(-1385 1685);
DISPLAY 0.617021 (-1385 1685);
PAINT ORANGE (-1385 1685);
FORCEPROP 2 LASTPIN (-1375 1625) $PN 139
J 2
(-1385 1635);
DISPLAY 0.617021 (-1385 1635);
PAINT ORANGE (-1385 1635);
FORCEPROP 2 LASTPIN (-1375 3075) $PN 237
J 2
(-1385 3085);
DISPLAY 0.617021 (-1385 3085);
PAINT ORANGE (-1385 3085);
FORCEPROP 2 LASTPIN (-1375 3025) $PN 93
J 2
(-1385 3035);
DISPLAY 0.617021 (-1385 3035);
PAINT ORANGE (-1385 3035);
FORCEPROP 2 LASTPIN (-1375 2975) $PN 89
J 2
(-1385 2985);
DISPLAY 0.617021 (-1385 2985);
PAINT ORANGE (-1385 2985);
FORCEPROP 2 LASTPIN (-1375 2925) $PN 84
J 2
(-1385 2935);
DISPLAY 0.617021 (-1385 2935);
PAINT ORANGE (-1385 2935);
FORCEPROP 2 LASTPIN (-1375 1325) $PN 144
J 2
(-1385 1335);
DISPLAY 0.617021 (-1385 1335);
PAINT ORANGE (-1385 1335);
FORCEPROP 2 LASTPIN (-1375 1275) $PN 227
J 2
(-1385 1285);
DISPLAY 0.617021 (-1385 1285);
PAINT ORANGE (-1385 1285);
FORCEPROP 2 LASTPIN (-1375 1225) $PN 205
J 2
(-1385 1235);
DISPLAY 0.617021 (-1385 1235);
PAINT ORANGE (-1385 1235);
FORCEPROP 2 LASTPIN (-1375 2025) $PN 58
J 2
(-1385 2035);
DISPLAY 0.617021 (-1385 2035);
PAINT ORANGE (-1385 2035);
FORCEPROP 2 LASTPIN (-1375 2075) $PN 222
J 2
(-1385 2085);
DISPLAY 0.617021 (-1385 2085);
PAINT ORANGE (-1385 2085);
FORCEPROP 2 LASTPIN (-1375 2675) $PN 91
J 2
(-1385 2685);
DISPLAY 0.617021 (-1385 2685);
PAINT ORANGE (-1385 2685);
FORCEPROP 2 LASTPIN (-1375 2625) $PN 87
J 2
(-1385 2635);
DISPLAY 0.617021 (-1385 2635);
PAINT ORANGE (-1385 2635);
FORCEPROP 2 LASTPIN (-1375 1975) $PN 78
J 2
(-1385 1985);
DISPLAY 0.617021 (-1385 1985);
PAINT ORANGE (-1385 1985);
FORCEPROP 2 LASTPIN (-375 4475) $PN 273
J 0
(-365 4485);
DISPLAY 0.617021 (-365 4485);
PAINT ORANGE (-365 4485);
FORCEPROP 2 LASTPIN (-375 4425) $PN 128
J 0
(-365 4435);
DISPLAY 0.617021 (-365 4435);
PAINT ORANGE (-365 4435);
FORCEPROP 2 LASTPIN (-375 4375) $PN 282
J 0
(-365 4385);
DISPLAY 0.617021 (-365 4385);
PAINT ORANGE (-365 4385);
FORCEPROP 2 LASTPIN (-375 4325) $PN 137
J 0
(-365 4335);
DISPLAY 0.617021 (-365 4335);
PAINT ORANGE (-365 4335);
FORCEPROP 2 LASTPIN (-375 4275) $PN 275
J 0
(-365 4285);
DISPLAY 0.617021 (-365 4285);
PAINT ORANGE (-365 4285);
FORCEPROP 2 LASTPIN (-375 4225) $PN 130
J 0
(-365 4235);
DISPLAY 0.617021 (-365 4235);
PAINT ORANGE (-365 4235);
FORCEPROP 2 LASTPIN (-375 4125) $PN 124
J 0
(-365 4135);
DISPLAY 0.617021 (-365 4135);
PAINT ORANGE (-365 4135);
FORCEPROP 2 LASTPIN (-375 4075) $PN 262
J 0
(-365 4085);
DISPLAY 0.617021 (-365 4085);
PAINT ORANGE (-365 4085);
FORCEPROP 2 LASTPIN (-375 4025) $PN 117
J 0
(-365 4035);
DISPLAY 0.617021 (-365 4035);
PAINT ORANGE (-365 4035);
FORCEPROP 2 LASTPIN (-375 3925) $PN 126
J 0
(-365 3935);
DISPLAY 0.617021 (-365 3935);
PAINT ORANGE (-365 3935);
FORCEPROP 2 LASTPIN (-375 3875) $PN 264
J 0
(-365 3885);
DISPLAY 0.617021 (-365 3885);
PAINT ORANGE (-365 3885);
FORCEPROP 2 LASTPIN (-375 3825) $PN 119
J 0
(-365 3835);
DISPLAY 0.617021 (-365 3835);
PAINT ORANGE (-365 3835);
FORCEPROP 2 LASTPIN (-375 3775) $PN 258
J 0
(-365 3785);
DISPLAY 0.617021 (-365 3785);
PAINT ORANGE (-365 3785);
FORCEPROP 2 LASTPIN (-375 3725) $PN 113
J 0
(-365 3735);
DISPLAY 0.617021 (-365 3735);
PAINT ORANGE (-365 3735);
FORCEPROP 2 LASTPIN (-375 3675) $PN 251
J 0
(-365 3685);
DISPLAY 0.617021 (-365 3685);
PAINT ORANGE (-365 3685);
FORCEPROP 2 LASTPIN (-375 3625) $PN 106
J 0
(-365 3635);
DISPLAY 0.617021 (-365 3635);
PAINT ORANGE (-365 3635);
FORCEPROP 2 LASTPIN (-375 3575) $PN 260
J 0
(-365 3585);
DISPLAY 0.617021 (-365 3585);
PAINT ORANGE (-365 3585);
FORCEPROP 2 LASTPIN (-375 3525) $PN 115
J 0
(-365 3535);
DISPLAY 0.617021 (-365 3535);
PAINT ORANGE (-365 3535);
FORCEPROP 2 LASTPIN (-375 3475) $PN 253
J 0
(-365 3485);
DISPLAY 0.617021 (-365 3485);
PAINT ORANGE (-365 3485);
FORCEPROP 2 LASTPIN (-375 3425) $PN 108
J 0
(-365 3435);
DISPLAY 0.617021 (-365 3435);
PAINT ORANGE (-365 3435);
FORCEPROP 2 LASTPIN (-375 3375) $PN 247
J 0
(-365 3385);
DISPLAY 0.617021 (-365 3385);
PAINT ORANGE (-365 3385);
FORCEPROP 2 LASTPIN (-375 3325) $PN 102
J 0
(-365 3335);
DISPLAY 0.617021 (-365 3335);
PAINT ORANGE (-365 3335);
FORCEPROP 2 LASTPIN (-375 3275) $PN 240
J 0
(-365 3285);
DISPLAY 0.617021 (-365 3285);
PAINT ORANGE (-365 3285);
FORCEPROP 2 LASTPIN (-375 3225) $PN 95
J 0
(-365 3235);
DISPLAY 0.617021 (-365 3235);
PAINT ORANGE (-365 3235);
FORCEPROP 2 LASTPIN (-375 3175) $PN 249
J 0
(-365 3185);
DISPLAY 0.617021 (-365 3185);
PAINT ORANGE (-365 3185);
FORCEPROP 2 LASTPIN (-375 3125) $PN 104
J 0
(-365 3135);
DISPLAY 0.617021 (-365 3135);
PAINT ORANGE (-365 3135);
FORCEPROP 2 LASTPIN (-375 3075) $PN 242
J 0
(-365 3085);
DISPLAY 0.617021 (-365 3085);
PAINT ORANGE (-365 3085);
FORCEPROP 2 LASTPIN (-375 3025) $PN 97
J 0
(-365 3035);
DISPLAY 0.617021 (-365 3035);
PAINT ORANGE (-365 3035);
FORCEPROP 2 LASTPIN (-375 2975) $PN 188
J 0
(-365 2985);
DISPLAY 0.617021 (-365 2985);
PAINT ORANGE (-365 2985);
FORCEPROP 2 LASTPIN (-375 2925) $PN 43
J 0
(-365 2935);
DISPLAY 0.617021 (-365 2935);
PAINT ORANGE (-365 2935);
FORCEPROP 2 LASTPIN (-375 2875) $PN 181
J 0
(-365 2885);
DISPLAY 0.617021 (-365 2885);
PAINT ORANGE (-365 2885);
FORCEPROP 2 LASTPIN (-375 2825) $PN 36
J 0
(-365 2835);
DISPLAY 0.617021 (-365 2835);
PAINT ORANGE (-365 2835);
FORCEPROP 2 LASTPIN (-375 2775) $PN 190
J 0
(-365 2785);
DISPLAY 0.617021 (-365 2785);
PAINT ORANGE (-365 2785);
FORCEPROP 2 LASTPIN (-375 2725) $PN 45
J 0
(-365 2735);
DISPLAY 0.617021 (-365 2735);
PAINT ORANGE (-365 2735);
FORCEPROP 2 LASTPIN (-375 2675) $PN 183
J 0
(-365 2685);
DISPLAY 0.617021 (-365 2685);
PAINT ORANGE (-365 2685);
FORCEPROP 2 LASTPIN (-375 2625) $PN 38
J 0
(-365 2635);
DISPLAY 0.617021 (-365 2635);
PAINT ORANGE (-365 2635);
FORCEPROP 2 LASTPIN (-375 2575) $PN 177
J 0
(-365 2585);
DISPLAY 0.617021 (-365 2585);
PAINT ORANGE (-365 2585);
FORCEPROP 2 LASTPIN (-375 2525) $PN 32
J 0
(-365 2535);
DISPLAY 0.617021 (-365 2535);
PAINT ORANGE (-365 2535);
FORCEPROP 2 LASTPIN (-375 2475) $PN 170
J 0
(-365 2485);
DISPLAY 0.617021 (-365 2485);
PAINT ORANGE (-365 2485);
FORCEPROP 2 LASTPIN (-375 2425) $PN 25
J 0
(-365 2435);
DISPLAY 0.617021 (-365 2435);
PAINT ORANGE (-365 2435);
FORCEPROP 2 LASTPIN (-375 2375) $PN 179
J 0
(-365 2385);
DISPLAY 0.617021 (-365 2385);
PAINT ORANGE (-365 2385);
FORCEPROP 2 LASTPIN (-375 2325) $PN 34
J 0
(-365 2335);
DISPLAY 0.617021 (-365 2335);
PAINT ORANGE (-365 2335);
FORCEPROP 2 LASTPIN (-375 2275) $PN 172
J 0
(-365 2285);
DISPLAY 0.617021 (-365 2285);
PAINT ORANGE (-365 2285);
FORCEPROP 2 LASTPIN (-375 2225) $PN 27
J 0
(-365 2235);
DISPLAY 0.617021 (-365 2235);
PAINT ORANGE (-365 2235);
FORCEPROP 2 LASTPIN (-375 2175) $PN 166
J 0
(-365 2185);
DISPLAY 0.617021 (-365 2185);
PAINT ORANGE (-365 2185);
FORCEPROP 2 LASTPIN (-375 2125) $PN 21
J 0
(-365 2135);
DISPLAY 0.617021 (-365 2135);
PAINT ORANGE (-365 2135);
FORCEPROP 2 LASTPIN (-375 2075) $PN 159
J 0
(-365 2085);
DISPLAY 0.617021 (-365 2085);
PAINT ORANGE (-365 2085);
FORCEPROP 2 LASTPIN (-375 2025) $PN 14
J 0
(-365 2035);
DISPLAY 0.617021 (-365 2035);
PAINT ORANGE (-365 2035);
FORCEPROP 2 LASTPIN (-375 1975) $PN 168
J 0
(-365 1985);
DISPLAY 0.617021 (-365 1985);
PAINT ORANGE (-365 1985);
FORCEPROP 2 LASTPIN (-375 1925) $PN 23
J 0
(-365 1935);
DISPLAY 0.617021 (-365 1935);
PAINT ORANGE (-365 1935);
FORCEPROP 2 LASTPIN (-375 1875) $PN 161
J 0
(-365 1885);
DISPLAY 0.617021 (-365 1885);
PAINT ORANGE (-365 1885);
FORCEPROP 2 LASTPIN (-375 1825) $PN 16
J 0
(-365 1835);
DISPLAY 0.617021 (-365 1835);
PAINT ORANGE (-365 1835);
FORCEPROP 2 LASTPIN (-375 1775) $PN 155
J 0
(-365 1785);
DISPLAY 0.617021 (-365 1785);
PAINT ORANGE (-365 1785);
FORCEPROP 2 LASTPIN (-375 1725) $PN 10
J 0
(-365 1735);
DISPLAY 0.617021 (-365 1735);
PAINT ORANGE (-365 1735);
FORCEPROP 2 LASTPIN (-375 1675) $PN 148
J 0
(-365 1685);
DISPLAY 0.617021 (-365 1685);
PAINT ORANGE (-365 1685);
FORCEPROP 2 LASTPIN (-375 1625) $PN 3
J 0
(-365 1635);
DISPLAY 0.617021 (-365 1635);
PAINT ORANGE (-365 1635);
FORCEPROP 2 LASTPIN (-375 1575) $PN 157
J 0
(-365 1585);
DISPLAY 0.617021 (-365 1585);
PAINT ORANGE (-365 1585);
FORCEPROP 2 LASTPIN (-375 1525) $PN 12
J 0
(-365 1535);
DISPLAY 0.617021 (-365 1535);
PAINT ORANGE (-365 1535);
FORCEPROP 2 LASTPIN (-375 1475) $PN 150
J 0
(-365 1485);
DISPLAY 0.617021 (-365 1485);
PAINT ORANGE (-365 1485);
FORCEPROP 2 LASTPIN (-1375 2825) $PN 203
J 2
(-1385 2835);
DISPLAY 0.617021 (-1385 2835);
PAINT ORANGE (-1385 2835);
FORCEPROP 2 LASTPIN (-1375 2775) $PN 60
J 2
(-1385 2785);
DISPLAY 0.617021 (-1385 2785);
PAINT ORANGE (-1385 2785);
FORCEPROP 2 LASTPIN (-1375 3375) $PN 218
J 2
(-1385 3385);
DISPLAY 0.617021 (-1385 3385);
PAINT ORANGE (-1385 3385);
FORCEPROP 2 LASTPIN (-1375 3325) $PN 219
J 2
(-1385 3335);
DISPLAY 0.617021 (-1385 3335);
PAINT ORANGE (-1385 3335);
FORCEPROP 2 LASTPIN (-1375 3275) $PN 74
J 2
(-1385 3285);
DISPLAY 0.617021 (-1385 3285);
PAINT ORANGE (-1385 3285);
FORCEPROP 2 LASTPIN (-1375 3225) $PN 75
J 2
(-1385 3235);
DISPLAY 0.617021 (-1385 3235);
PAINT ORANGE (-1385 3235);
FORCEPROP 2 LASTPIN (-1375 2525) $PN 199
J 2
(-1385 2535);
DISPLAY 0.617021 (-1385 2535);
PAINT ORANGE (-1385 2535);
FORCEPROP 2 LASTPIN (-1375 2475) $PN 54
J 2
(-1385 2485);
DISPLAY 0.617021 (-1385 2485);
PAINT ORANGE (-1385 2485);
FORCEPROP 2 LASTPIN (-1375 2425) $PN 192
J 2
(-1385 2435);
DISPLAY 0.617021 (-1385 2435);
PAINT ORANGE (-1385 2435);
FORCEPROP 2 LASTPIN (-1375 2375) $PN 47
J 2
(-1385 2385);
DISPLAY 0.617021 (-1385 2385);
PAINT ORANGE (-1385 2385);
FORCEPROP 2 LASTPIN (-1375 2325) $PN 201
J 2
(-1385 2335);
DISPLAY 0.617021 (-1385 2335);
PAINT ORANGE (-1385 2335);
FORCEPROP 2 LASTPIN (-1375 2275) $PN 56
J 2
(-1385 2285);
DISPLAY 0.617021 (-1385 2285);
PAINT ORANGE (-1385 2285);
FORCEPROP 2 LASTPIN (-1375 2225) $PN 194
J 2
(-1385 2235);
DISPLAY 0.617021 (-1385 2235);
PAINT ORANGE (-1385 2235);
FORCEPROP 2 LASTPIN (-1375 2175) $PN 49
J 2
(-1385 2185);
DISPLAY 0.617021 (-1385 2185);
PAINT ORANGE (-1385 2185);
FORCEPROP 2 LASTPIN (-1375 3125) $PN 235
J 2
(-1385 3135);
DISPLAY 0.617021 (-1385 3135);
PAINT ORANGE (-1385 3135);
FORCEPROP 2 LASTPIN (-1375 3525) $PN 207
J 2
(-1385 3535);
DISPLAY 0.617021 (-1385 3535);
PAINT ORANGE (-1385 3535);
FORCEPROP 2 LASTPIN (-1375 3475) $PN 63
J 2
(-1385 3485);
DISPLAY 0.617021 (-1385 3485);
PAINT ORANGE (-1385 3485);
FORCEPROP 2 LASTPIN (-1375 3625) $PN 224
J 2
(-1385 3635);
DISPLAY 0.617021 (-1385 3635);
PAINT ORANGE (-1385 3635);
FORCEPROP 2 LASTPIN (-1375 3575) $PN 81
J 2
(-1385 3585);
DISPLAY 0.617021 (-1385 3585);
PAINT ORANGE (-1385 3585);
FORCEPROP 2 LASTPIN (-1375 1925) $PN 208
J 2
(-1385 1935);
DISPLAY 0.617021 (-1385 1935);
PAINT ORANGE (-1385 1935);
FORCEPROP 2 LASTPIN (-1375 1875) $PN 62
J 2
(-1385 1885);
DISPLAY 0.617021 (-1385 1885);
PAINT ORANGE (-1385 1885);
FORCEPROP 2 LASTPIN (-1375 4525) $PN 82
J 2
(-1385 4535);
DISPLAY 0.617021 (-1385 4535);
PAINT ORANGE (-1385 4535);
FORCEPROP 2 LASTPIN (-1375 4475) $PN 86
J 2
(-1385 4485);
DISPLAY 0.617021 (-1385 4485);
PAINT ORANGE (-1385 4485);
FORCEPROP 2 LASTPIN (-1375 4425) $PN 228
J 2
(-1385 4435);
DISPLAY 0.617021 (-1385 4435);
PAINT ORANGE (-1385 4435);
FORCEPROP 2 LASTPIN (-1375 4375) $PN 232
J 2
(-1385 4385);
DISPLAY 0.617021 (-1385 4385);
PAINT ORANGE (-1385 4385);
FORCEPROP 2 LASTPIN (-1375 4325) $PN 65
J 2
(-1385 4335);
DISPLAY 0.617021 (-1385 4335);
PAINT ORANGE (-1385 4335);
FORCEPROP 2 LASTPIN (-1375 4275) $PN 210
J 2
(-1385 4285);
DISPLAY 0.617021 (-1385 4285);
PAINT ORANGE (-1385 4285);
FORCEPROP 2 LASTPIN (-1375 4225) $PN 225
J 2
(-1385 4235);
DISPLAY 0.617021 (-1385 4235);
PAINT ORANGE (-1385 4235);
FORCEPROP 2 LASTPIN (-1375 4175) $PN 66
J 2
(-1385 4185);
DISPLAY 0.617021 (-1385 4185);
PAINT ORANGE (-1385 4185);
FORCEPROP 2 LASTPIN (-1375 4125) $PN 68
J 2
(-1385 4135);
DISPLAY 0.617021 (-1385 4135);
PAINT ORANGE (-1385 4135);
FORCEPROP 2 LASTPIN (-1375 4075) $PN 211
J 2
(-1385 4085);
DISPLAY 0.617021 (-1385 4085);
PAINT ORANGE (-1385 4085);
FORCEPROP 2 LASTPIN (-1375 4025) $PN 69
J 2
(-1385 4035);
DISPLAY 0.617021 (-1385 4035);
PAINT ORANGE (-1385 4035);
FORCEPROP 2 LASTPIN (-1375 3975) $PN 213
J 2
(-1385 3985);
DISPLAY 0.617021 (-1385 3985);
PAINT ORANGE (-1385 3985);
FORCEPROP 2 LASTPIN (-1375 3925) $PN 214
J 2
(-1385 3935);
DISPLAY 0.617021 (-1385 3935);
PAINT ORANGE (-1385 3935);
FORCEPROP 2 LASTPIN (-1375 3875) $PN 71
J 2
(-1385 3885);
DISPLAY 0.617021 (-1385 3885);
PAINT ORANGE (-1385 3885);
FORCEPROP 2 LASTPIN (-1375 3825) $PN 216
J 2
(-1385 3835);
DISPLAY 0.617021 (-1385 3835);
PAINT ORANGE (-1385 3835);
FORCEPROP 2 LASTPIN (-1375 3775) $PN 72
J 2
(-1385 3785);
DISPLAY 0.617021 (-1385 3785);
PAINT ORANGE (-1385 3785);
FORCEPROP 2 LASTPIN (-1375 3725) $PN 79
J 2
(-1385 3735);
DISPLAY 0.617021 (-1385 3735);
PAINT ORANGE (-1385 3735);
FORCEPROP 2 LASTPIN (-375 1425) $PN 5
J 0
(-365 1435);
DISPLAY 0.617021 (-365 1435);
PAINT ORANGE (-365 1435);
FORCEPROP 2 LASTPIN (-375 3975) $PN 271
J 0
(-365 3985);
DISPLAY 0.617021 (-365 3985);
PAINT ORANGE (-365 3985);
FORCEPROP 2 LASTPIN (-375 4175) $PN 269
J 0
(-365 4185);
DISPLAY 0.617021 (-365 4185);
PAINT ORANGE (-365 4185);
FORCEPROP 2 LASTPIN (-375 4525) $PN 135
J 0
(-365 4535);
DISPLAY 0.617021 (-365 4535);
PAINT ORANGE (-365 4535);
FORCEPROP 2 LASTPIN (-375 4575) $PN 280
J 0
(-365 4585);
DISPLAY 0.617021 (-365 4585);
PAINT ORANGE (-365 4585);
FORCEPROP 0 LAST BOM_SS NOPOP
J 0
(-1019 4774);
DISPLAY 1.021277 (-1019 4774);
PAINT BROWN (-1019 4774);
DISPLAY BOTH (-1019 4774);
FORCEPROP 1 LAST PACK_TYPE PIP
J 0
(-1325 4875);
PAINT SKYBLUE (-1325 4875);
DISPLAY INVISIBLE (-1325 4875);
FORCEPROP 2 LAST BOM_COST MEM
J 0
(-875 2925);
PAINT ORANGE (-875 2925);
DISPLAY INVISIBLE (-875 2925);
FORCEPROP 2 LAST CDS_LIB mstr_sconn
J 0
(-875 2925);
PAINT ORANGE (-875 2925);
DISPLAY INVISIBLE (-875 2925);
FORCEPROP 2 LAST SEC_TYPE PIP
J 0
(-1325 4875);
DISPLAY 1.021277 (-1325 4875);
PAINT ORANGE (-1325 4875);
DISPLAY INVISIBLE (-1325 4875);
FORCEPROP 2 LAST SEC 1
J 0
(-1325 4875);
DISPLAY 0.680851 (-1325 4875);
PAINT MONO (-1325 4875);
DISPLAY INVISIBLE (-1325 4875);
FORCEPROP 2 LAST CDS_LOCATION J9L2
J 0
(-1325 4825);
DISPLAY 0.617021 (-1325 4825);
PAINT AQUA (-1325 4825);
DISPLAY INVISIBLE (-1325 4825);
FORCEPROP 1 LAST PATH I12
J 0
(-875 4775);
PAINT GREEN (-875 4775);
DISPLAY INVISIBLE (-875 4775);
FORCEPROP 2 LAST ROOM DDR4_CH_L
J 0
(-875 2925);
PAINT ORANGE (-875 2925);
DISPLAY INVISIBLE (-875 2925);
FORCEADD TAP..6
R 2
(-125 3975);
FORCEPROP 3 LASTPIN (-175 3975) SIG_NAME M_L_DQ<51>
J 0
(-165 3985);
DISPLAY 0.659574 (-165 3985);
PAINT MONO (-165 3985);
DISPLAY INVISIBLE (-165 3985);
FORCEPROP 1 LASTPIN (-175 3975) BN 51
J 2
(-125 3985);
DISPLAY 0.617021 (-125 3985);
PAINT PINK (-125 3985);
FORCEPROP 2 LAST CDS_LIB mstr_standard
J 2
(-125 3975);
DISPLAY 0.787234 (-125 3975);
PAINT MONO (-125 3975);
DISPLAY INVISIBLE (-125 3975);
FORCEPROP 1 LAST BODY_TYPE PLUMBING
J 2
(-125 3925);
DISPLAY 1.234043 (-125 3925);
PAINT GREEN (-125 3925);
DISPLAY INVISIBLE (-125 3925);
FORCEPROP 1 LAST HDL_TAP TRUE
J 2
(-450 3850);
DISPLAY 1.234043 (-450 3850);
PAINT GREEN (-450 3850);
DISPLAY INVISIBLE (-450 3850);
FORCEPROP 1 LAST PATH I120
J 2
(-123 3975);
DISPLAY 0.872340 (-123 3975);
PAINT GREEN (-123 3975);
DISPLAY INVISIBLE (-123 3975);
FORCEADD TAP..6
R 2
(-125 3875);
FORCEPROP 3 LASTPIN (-175 3875) SIG_NAME M_L_DQ<49>
J 0
(-165 3885);
DISPLAY 0.659574 (-165 3885);
PAINT MONO (-165 3885);
DISPLAY INVISIBLE (-165 3885);
FORCEPROP 1 LASTPIN (-175 3875) BN 49
J 2
(-125 3885);
DISPLAY 0.617021 (-125 3885);
PAINT PINK (-125 3885);
FORCEPROP 2 LAST CDS_LIB mstr_standard
J 2
(-125 3875);
DISPLAY 0.787234 (-125 3875);
PAINT MONO (-125 3875);
DISPLAY INVISIBLE (-125 3875);
FORCEPROP 1 LAST BODY_TYPE PLUMBING
J 2
(-125 3825);
DISPLAY 1.234043 (-125 3825);
PAINT GREEN (-125 3825);
DISPLAY INVISIBLE (-125 3825);
FORCEPROP 1 LAST HDL_TAP TRUE
J 2
(-450 3750);
DISPLAY 1.234043 (-450 3750);
PAINT GREEN (-450 3750);
DISPLAY INVISIBLE (-450 3750);
FORCEPROP 1 LAST PATH I121
J 2
(-123 3875);
DISPLAY 0.872340 (-123 3875);
PAINT GREEN (-123 3875);
DISPLAY INVISIBLE (-123 3875);
FORCEADD TAP..6
R 2
(-125 3775);
FORCEPROP 3 LASTPIN (-175 3775) SIG_NAME M_L_DQ<47>
J 0
(-165 3785);
DISPLAY 0.659574 (-165 3785);
PAINT MONO (-165 3785);
DISPLAY INVISIBLE (-165 3785);
FORCEPROP 1 LASTPIN (-175 3775) BN 47
J 2
(-125 3785);
DISPLAY 0.617021 (-125 3785);
PAINT PINK (-125 3785);
FORCEPROP 2 LAST CDS_LIB mstr_standard
J 2
(-125 3775);
DISPLAY 0.787234 (-125 3775);
PAINT MONO (-125 3775);
DISPLAY INVISIBLE (-125 3775);
FORCEPROP 1 LAST BODY_TYPE PLUMBING
J 2
(-125 3725);
DISPLAY 1.234043 (-125 3725);
PAINT GREEN (-125 3725);
DISPLAY INVISIBLE (-125 3725);
FORCEPROP 1 LAST HDL_TAP TRUE
J 2
(-450 3650);
DISPLAY 1.234043 (-450 3650);
PAINT GREEN (-450 3650);
DISPLAY INVISIBLE (-450 3650);
FORCEPROP 1 LAST PATH I122
J 2
(-123 3775);
DISPLAY 0.872340 (-123 3775);
PAINT GREEN (-123 3775);
DISPLAY INVISIBLE (-123 3775);
FORCEADD TAP..6
R 2
(-125 3825);
FORCEPROP 3 LASTPIN (-175 3825) SIG_NAME M_L_DQ<48>
J 0
(-165 3835);
DISPLAY 0.659574 (-165 3835);
PAINT MONO (-165 3835);
DISPLAY INVISIBLE (-165 3835);
FORCEPROP 1 LASTPIN (-175 3825) BN 48
J 2
(-125 3835);
DISPLAY 0.617021 (-125 3835);
PAINT PINK (-125 3835);
FORCEPROP 2 LAST CDS_LIB mstr_standard
J 2
(-125 3825);
DISPLAY 0.787234 (-125 3825);
PAINT MONO (-125 3825);
DISPLAY INVISIBLE (-125 3825);
FORCEPROP 1 LAST BODY_TYPE PLUMBING
J 2
(-125 3775);
DISPLAY 1.234043 (-125 3775);
PAINT GREEN (-125 3775);
DISPLAY INVISIBLE (-125 3775);
FORCEPROP 1 LAST HDL_TAP TRUE
J 2
(-450 3700);
DISPLAY 1.234043 (-450 3700);
PAINT GREEN (-450 3700);
DISPLAY INVISIBLE (-450 3700);
FORCEPROP 1 LAST PATH I123
J 2
(-123 3825);
DISPLAY 0.872340 (-123 3825);
PAINT GREEN (-123 3825);
DISPLAY INVISIBLE (-123 3825);
FORCEADD TAP..6
R 2
(-125 4025);
FORCEPROP 3 LASTPIN (-175 4025) SIG_NAME M_L_DQ<52>
J 0
(-165 4035);
DISPLAY 0.659574 (-165 4035);
PAINT MONO (-165 4035);
DISPLAY INVISIBLE (-165 4035);
FORCEPROP 1 LASTPIN (-175 4025) BN 52
J 2
(-125 4035);
DISPLAY 0.617021 (-125 4035);
PAINT PINK (-125 4035);
FORCEPROP 2 LAST CDS_LIB mstr_standard
J 2
(-125 4025);
DISPLAY 0.787234 (-125 4025);
PAINT MONO (-125 4025);
DISPLAY INVISIBLE (-125 4025);
FORCEPROP 1 LAST BODY_TYPE PLUMBING
J 2
(-125 3975);
DISPLAY 1.234043 (-125 3975);
PAINT GREEN (-125 3975);
DISPLAY INVISIBLE (-125 3975);
FORCEPROP 1 LAST HDL_TAP TRUE
J 2
(-450 3900);
DISPLAY 1.234043 (-450 3900);
PAINT GREEN (-450 3900);
DISPLAY INVISIBLE (-450 3900);
FORCEPROP 1 LAST PATH I124
J 2
(-123 4025);
DISPLAY 0.872340 (-123 4025);
PAINT GREEN (-123 4025);
DISPLAY INVISIBLE (-123 4025);
FORCEADD TAP..6
R 2
(-125 4175);
FORCEPROP 3 LASTPIN (-175 4175) SIG_NAME M_L_DQ<55>
J 0
(-165 4185);
DISPLAY 0.659574 (-165 4185);
PAINT MONO (-165 4185);
DISPLAY INVISIBLE (-165 4185);
FORCEPROP 1 LASTPIN (-175 4175) BN 55
J 2
(-125 4185);
DISPLAY 0.617021 (-125 4185);
PAINT PINK (-125 4185);
FORCEPROP 2 LAST CDS_LIB mstr_standard
J 2
(-125 4175);
DISPLAY 0.787234 (-125 4175);
PAINT MONO (-125 4175);
DISPLAY INVISIBLE (-125 4175);
FORCEPROP 1 LAST BODY_TYPE PLUMBING
J 2
(-125 4125);
DISPLAY 1.234043 (-125 4125);
PAINT GREEN (-125 4125);
DISPLAY INVISIBLE (-125 4125);
FORCEPROP 1 LAST HDL_TAP TRUE
J 2
(-450 4050);
DISPLAY 1.234043 (-450 4050);
PAINT GREEN (-450 4050);
DISPLAY INVISIBLE (-450 4050);
FORCEPROP 1 LAST PATH I125
J 2
(-123 4175);
DISPLAY 0.872340 (-123 4175);
PAINT GREEN (-123 4175);
DISPLAY INVISIBLE (-123 4175);
FORCEADD TAP..6
R 2
(-125 4225);
FORCEPROP 3 LASTPIN (-175 4225) SIG_NAME M_L_DQ<56>
J 0
(-165 4235);
DISPLAY 0.659574 (-165 4235);
PAINT MONO (-165 4235);
DISPLAY INVISIBLE (-165 4235);
FORCEPROP 1 LASTPIN (-175 4225) BN 56
J 2
(-125 4235);
DISPLAY 0.617021 (-125 4235);
PAINT PINK (-125 4235);
FORCEPROP 2 LAST CDS_LIB mstr_standard
J 2
(-125 4225);
DISPLAY 0.787234 (-125 4225);
PAINT MONO (-125 4225);
DISPLAY INVISIBLE (-125 4225);
FORCEPROP 1 LAST BODY_TYPE PLUMBING
J 2
(-125 4175);
DISPLAY 1.234043 (-125 4175);
PAINT GREEN (-125 4175);
DISPLAY INVISIBLE (-125 4175);
FORCEPROP 1 LAST HDL_TAP TRUE
J 2
(-450 4100);
DISPLAY 1.234043 (-450 4100);
PAINT GREEN (-450 4100);
DISPLAY INVISIBLE (-450 4100);
FORCEPROP 1 LAST PATH I126
J 2
(-123 4225);
DISPLAY 0.872340 (-123 4225);
PAINT GREEN (-123 4225);
DISPLAY INVISIBLE (-123 4225);
FORCEADD TAP..6
R 2
(-125 4275);
FORCEPROP 3 LASTPIN (-175 4275) SIG_NAME M_L_DQ<57>
J 0
(-165 4285);
DISPLAY 0.659574 (-165 4285);
PAINT MONO (-165 4285);
DISPLAY INVISIBLE (-165 4285);
FORCEPROP 1 LASTPIN (-175 4275) BN 57
J 2
(-125 4285);
DISPLAY 0.617021 (-125 4285);
PAINT PINK (-125 4285);
FORCEPROP 2 LAST CDS_LIB mstr_standard
J 2
(-125 4275);
DISPLAY 0.787234 (-125 4275);
PAINT MONO (-125 4275);
DISPLAY INVISIBLE (-125 4275);
FORCEPROP 1 LAST BODY_TYPE PLUMBING
J 2
(-125 4225);
DISPLAY 1.234043 (-125 4225);
PAINT GREEN (-125 4225);
DISPLAY INVISIBLE (-125 4225);
FORCEPROP 1 LAST HDL_TAP TRUE
J 2
(-450 4150);
DISPLAY 1.234043 (-450 4150);
PAINT GREEN (-450 4150);
DISPLAY INVISIBLE (-450 4150);
FORCEPROP 1 LAST PATH I127
J 2
(-123 4275);
DISPLAY 0.872340 (-123 4275);
PAINT GREEN (-123 4275);
DISPLAY INVISIBLE (-123 4275);
FORCEADD TAP..6
R 2
(-125 4075);
FORCEPROP 3 LASTPIN (-175 4075) SIG_NAME M_L_DQ<53>
J 0
(-165 4085);
DISPLAY 0.659574 (-165 4085);
PAINT MONO (-165 4085);
DISPLAY INVISIBLE (-165 4085);
FORCEPROP 1 LASTPIN (-175 4075) BN 53
J 2
(-125 4085);
DISPLAY 0.617021 (-125 4085);
PAINT PINK (-125 4085);
FORCEPROP 2 LAST CDS_LIB mstr_standard
J 2
(-125 4075);
DISPLAY 0.787234 (-125 4075);
PAINT MONO (-125 4075);
DISPLAY INVISIBLE (-125 4075);
FORCEPROP 1 LAST BODY_TYPE PLUMBING
J 2
(-125 4025);
DISPLAY 1.234043 (-125 4025);
PAINT GREEN (-125 4025);
DISPLAY INVISIBLE (-125 4025);
FORCEPROP 1 LAST HDL_TAP TRUE
J 2
(-450 3950);
DISPLAY 1.234043 (-450 3950);
PAINT GREEN (-450 3950);
DISPLAY INVISIBLE (-450 3950);
FORCEPROP 1 LAST PATH I128
J 2
(-123 4075);
DISPLAY 0.872340 (-123 4075);
PAINT GREEN (-123 4075);
DISPLAY INVISIBLE (-123 4075);
FORCEADD TAP..6
R 2
(-125 4125);
FORCEPROP 3 LASTPIN (-175 4125) SIG_NAME M_L_DQ<54>
J 0
(-165 4135);
DISPLAY 0.659574 (-165 4135);
PAINT MONO (-165 4135);
DISPLAY INVISIBLE (-165 4135);
FORCEPROP 1 LASTPIN (-175 4125) BN 54
J 2
(-125 4135);
DISPLAY 0.617021 (-125 4135);
PAINT PINK (-125 4135);
FORCEPROP 2 LAST CDS_LIB mstr_standard
J 2
(-125 4125);
DISPLAY 0.787234 (-125 4125);
PAINT MONO (-125 4125);
DISPLAY INVISIBLE (-125 4125);
FORCEPROP 1 LAST BODY_TYPE PLUMBING
J 2
(-125 4075);
DISPLAY 1.234043 (-125 4075);
PAINT GREEN (-125 4075);
DISPLAY INVISIBLE (-125 4075);
FORCEPROP 1 LAST HDL_TAP TRUE
J 2
(-450 4000);
DISPLAY 1.234043 (-450 4000);
PAINT GREEN (-450 4000);
DISPLAY INVISIBLE (-450 4000);
FORCEPROP 1 LAST PATH I129
J 2
(-123 4125);
DISPLAY 0.872340 (-123 4125);
PAINT GREEN (-123 4125);
DISPLAY INVISIBLE (-123 4125);
FORCEADD OFFPAGE..1
(-2225 2475);
FORCEPROP 2 LAST $XR5 88 
J 0
(-2926 2475);
DISPLAY 0.638298 (-2926 2475);
PAINT MONO (-2926 2475);
FORCEPROP 2 LAST $XR4 87 
J 0
(-2836 2475);
DISPLAY 0.638298 (-2836 2475);
PAINT MONO (-2836 2475);
FORCEPROP 2 LAST $XR3 85 
J 0
(-2746 2475);
DISPLAY 0.638298 (-2746 2475);
PAINT MONO (-2746 2475);
FORCEPROP 2 LAST $XR2 84 
J 0
(-2656 2475);
DISPLAY 0.638298 (-2656 2475);
PAINT MONO (-2656 2475);
FORCEPROP 2 LAST $XR1 83 
J 0
(-2566 2475);
DISPLAY 0.638298 (-2566 2475);
PAINT MONO (-2566 2475);
FORCEPROP 2 LAST $XR0 55 
J 0
(-2476 2475);
DISPLAY 0.638298 (-2476 2475);
PAINT MONO (-2476 2475);
FORCEPROP 2 LAST CDS_LIB mstr_standard
J 0
(-2225 2475);
DISPLAY 0.787234 (-2225 2475);
PAINT MONO (-2225 2475);
DISPLAY INVISIBLE (-2225 2475);
FORCEPROP 1 LAST OFFPAGE TRUE
J 0
(-1900 2350);
DISPLAY 0.936170 (-1900 2350);
PAINT GREEN (-1900 2350);
DISPLAY INVISIBLE (-1900 2350);
FORCEPROP 1 LAST COMMENT_BODY TRUE
J 0
(-2100 2375);
DISPLAY 0.936170 (-2100 2375);
PAINT GREEN (-2100 2375);
DISPLAY INVISIBLE (-2100 2375);
FORCEPROP 2 LAST PATH I13
J 0
(-2475 2525);
DISPLAY 1.021277 (-2475 2525);
PAINT ORANGE (-2475 2525);
DISPLAY INVISIBLE (-2475 2525);
FORCEADD TAP..6
R 2
(-125 4375);
FORCEPROP 3 LASTPIN (-175 4375) SIG_NAME M_L_DQ<59>
J 0
(-165 4385);
DISPLAY 0.659574 (-165 4385);
PAINT MONO (-165 4385);
DISPLAY INVISIBLE (-165 4385);
FORCEPROP 1 LASTPIN (-175 4375) BN 59
J 2
(-125 4385);
DISPLAY 0.617021 (-125 4385);
PAINT PINK (-125 4385);
FORCEPROP 2 LAST CDS_LIB mstr_standard
J 2
(-125 4375);
DISPLAY 0.787234 (-125 4375);
PAINT MONO (-125 4375);
DISPLAY INVISIBLE (-125 4375);
FORCEPROP 1 LAST BODY_TYPE PLUMBING
J 2
(-125 4325);
DISPLAY 1.234043 (-125 4325);
PAINT GREEN (-125 4325);
DISPLAY INVISIBLE (-125 4325);
FORCEPROP 1 LAST HDL_TAP TRUE
J 2
(-450 4250);
DISPLAY 1.234043 (-450 4250);
PAINT GREEN (-450 4250);
DISPLAY INVISIBLE (-450 4250);
FORCEPROP 1 LAST PATH I130
J 2
(-123 4375);
DISPLAY 0.872340 (-123 4375);
PAINT GREEN (-123 4375);
DISPLAY INVISIBLE (-123 4375);
FORCEADD TAP..6
R 2
(-125 4325);
FORCEPROP 3 LASTPIN (-175 4325) SIG_NAME M_L_DQ<58>
J 0
(-165 4335);
DISPLAY 0.659574 (-165 4335);
PAINT MONO (-165 4335);
DISPLAY INVISIBLE (-165 4335);
FORCEPROP 1 LASTPIN (-175 4325) BN 58
J 2
(-125 4335);
DISPLAY 0.617021 (-125 4335);
PAINT PINK (-125 4335);
FORCEPROP 2 LAST CDS_LIB mstr_standard
J 2
(-125 4325);
DISPLAY 0.787234 (-125 4325);
PAINT MONO (-125 4325);
DISPLAY INVISIBLE (-125 4325);
FORCEPROP 1 LAST BODY_TYPE PLUMBING
J 2
(-125 4275);
DISPLAY 1.234043 (-125 4275);
PAINT GREEN (-125 4275);
DISPLAY INVISIBLE (-125 4275);
FORCEPROP 1 LAST HDL_TAP TRUE
J 2
(-450 4200);
DISPLAY 1.234043 (-450 4200);
PAINT GREEN (-450 4200);
DISPLAY INVISIBLE (-450 4200);
FORCEPROP 1 LAST PATH I131
J 2
(-123 4325);
DISPLAY 0.872340 (-123 4325);
PAINT GREEN (-123 4325);
DISPLAY INVISIBLE (-123 4325);
FORCEADD TAP..6
R 2
(-125 4525);
FORCEPROP 3 LASTPIN (-175 4525) SIG_NAME M_L_DQ<62>
J 0
(-165 4535);
DISPLAY 0.659574 (-165 4535);
PAINT MONO (-165 4535);
DISPLAY INVISIBLE (-165 4535);
FORCEPROP 1 LASTPIN (-175 4525) BN 62
J 2
(-125 4535);
DISPLAY 0.617021 (-125 4535);
PAINT PINK (-125 4535);
FORCEPROP 2 LAST CDS_LIB mstr_standard
J 2
(-125 4525);
DISPLAY 0.787234 (-125 4525);
PAINT MONO (-125 4525);
DISPLAY INVISIBLE (-125 4525);
FORCEPROP 1 LAST BODY_TYPE PLUMBING
J 2
(-125 4475);
DISPLAY 1.234043 (-125 4475);
PAINT GREEN (-125 4475);
DISPLAY INVISIBLE (-125 4475);
FORCEPROP 1 LAST HDL_TAP TRUE
J 2
(-450 4400);
DISPLAY 1.234043 (-450 4400);
PAINT GREEN (-450 4400);
DISPLAY INVISIBLE (-450 4400);
FORCEPROP 1 LAST PATH I132
J 2
(-123 4525);
DISPLAY 0.872340 (-123 4525);
PAINT GREEN (-123 4525);
DISPLAY INVISIBLE (-123 4525);
FORCEADD TAP..6
R 2
(-125 4425);
FORCEPROP 3 LASTPIN (-175 4425) SIG_NAME M_L_DQ<60>
J 0
(-165 4435);
DISPLAY 0.659574 (-165 4435);
PAINT MONO (-165 4435);
DISPLAY INVISIBLE (-165 4435);
FORCEPROP 1 LASTPIN (-175 4425) BN 60
J 2
(-125 4435);
DISPLAY 0.617021 (-125 4435);
PAINT PINK (-125 4435);
FORCEPROP 2 LAST CDS_LIB mstr_standard
J 2
(-125 4425);
DISPLAY 0.787234 (-125 4425);
PAINT MONO (-125 4425);
DISPLAY INVISIBLE (-125 4425);
FORCEPROP 1 LAST BODY_TYPE PLUMBING
J 2
(-125 4375);
DISPLAY 1.234043 (-125 4375);
PAINT GREEN (-125 4375);
DISPLAY INVISIBLE (-125 4375);
FORCEPROP 1 LAST HDL_TAP TRUE
J 2
(-450 4300);
DISPLAY 1.234043 (-450 4300);
PAINT GREEN (-450 4300);
DISPLAY INVISIBLE (-450 4300);
FORCEPROP 1 LAST PATH I133
J 2
(-123 4425);
DISPLAY 0.872340 (-123 4425);
PAINT GREEN (-123 4425);
DISPLAY INVISIBLE (-123 4425);
FORCEADD TAP..6
R 2
(-125 4475);
FORCEPROP 3 LASTPIN (-175 4475) SIG_NAME M_L_DQ<61>
J 0
(-165 4485);
DISPLAY 0.659574 (-165 4485);
PAINT MONO (-165 4485);
DISPLAY INVISIBLE (-165 4485);
FORCEPROP 1 LASTPIN (-175 4475) BN 61
J 2
(-125 4485);
DISPLAY 0.617021 (-125 4485);
PAINT PINK (-125 4485);
FORCEPROP 2 LAST CDS_LIB mstr_standard
J 2
(-125 4475);
DISPLAY 0.787234 (-125 4475);
PAINT MONO (-125 4475);
DISPLAY INVISIBLE (-125 4475);
FORCEPROP 1 LAST BODY_TYPE PLUMBING
J 2
(-125 4425);
DISPLAY 1.234043 (-125 4425);
PAINT GREEN (-125 4425);
DISPLAY INVISIBLE (-125 4425);
FORCEPROP 1 LAST HDL_TAP TRUE
J 2
(-450 4350);
DISPLAY 1.234043 (-450 4350);
PAINT GREEN (-450 4350);
DISPLAY INVISIBLE (-450 4350);
FORCEPROP 1 LAST PATH I134
J 2
(-123 4475);
DISPLAY 0.872340 (-123 4475);
PAINT GREEN (-123 4475);
DISPLAY INVISIBLE (-123 4475);
FORCEADD TAP..6
R 2
(-125 4575);
FORCEPROP 3 LASTPIN (-175 4575) SIG_NAME M_L_DQ<63>
J 0
(-165 4585);
DISPLAY 0.659574 (-165 4585);
PAINT MONO (-165 4585);
DISPLAY INVISIBLE (-165 4585);
FORCEPROP 1 LASTPIN (-175 4575) BN 63
J 2
(-125 4585);
DISPLAY 0.617021 (-125 4585);
PAINT PINK (-125 4585);
FORCEPROP 2 LAST CDS_LIB mstr_standard
J 2
(-125 4575);
DISPLAY 0.787234 (-125 4575);
PAINT MONO (-125 4575);
DISPLAY INVISIBLE (-125 4575);
FORCEPROP 1 LAST BODY_TYPE PLUMBING
J 2
(-125 4525);
DISPLAY 1.234043 (-125 4525);
PAINT GREEN (-125 4525);
DISPLAY INVISIBLE (-125 4525);
FORCEPROP 1 LAST HDL_TAP TRUE
J 2
(-450 4450);
DISPLAY 1.234043 (-450 4450);
PAINT GREEN (-450 4450);
DISPLAY INVISIBLE (-450 4450);
FORCEPROP 1 LAST PATH I135
J 2
(-123 4575);
DISPLAY 0.872340 (-123 4575);
PAINT GREEN (-123 4575);
DISPLAY INVISIBLE (-123 4575);
FORCEADD OFFPAGE..3
(450 4625);
FORCEPROP 2 LAST $XR1 85 
J 0
(754 4625);
DISPLAY 0.638298 (754 4625);
PAINT MONO (754 4625);
FORCEPROP 2 LAST $XR0 61 
J 0
(664 4625);
DISPLAY 0.638298 (664 4625);
PAINT MONO (664 4625);
FORCEPROP 2 LAST CDS_LIB mstr_standard
J 0
(450 4625);
DISPLAY 0.787234 (450 4625);
PAINT MONO (450 4625);
DISPLAY INVISIBLE (450 4625);
FORCEPROP 1 LAST OFFPAGE TRUE
J 0
(775 4500);
DISPLAY 0.936170 (775 4500);
PAINT GREEN (775 4500);
DISPLAY INVISIBLE (775 4500);
FORCEPROP 1 LAST COMMENT_BODY TRUE
J 0
(400 4525);
DISPLAY 0.936170 (400 4525);
PAINT GREEN (400 4525);
DISPLAY INVISIBLE (400 4525);
FORCEPROP 2 LAST PATH I136
J 0
(675 4675);
DISPLAY 1.021277 (675 4675);
PAINT ORANGE (675 4675);
DISPLAY INVISIBLE (675 4675);
FORCEADD GND..1
R 2
(2725 775);
FORCEPROP 3 LASTPIN (2725 825) SIG_NAME GND\g
J 0
(2735 835);
DISPLAY 0.659574 (2735 835);
PAINT MONO (2735 835);
DISPLAY INVISIBLE (2735 835);
FORCEPROP 1 LAST VOLTAGE 0
J 0
(2725 775);
PAINT SKYBLUE (2725 775);
DISPLAY INVISIBLE (2725 775);
FORCEPROP 1 LAST SIZE 1B
J 2
(2650 725);
DISPLAY 1.170213 (2650 725);
PAINT GREEN (2650 725);
DISPLAY INVISIBLE (2650 725);
FORCEPROP 2 LAST CDS_LIB mstr_symbols
J 0
(2725 775);
DISPLAY 0.787234 (2725 775);
PAINT MONO (2725 775);
DISPLAY INVISIBLE (2725 775);
FORCEPROP 2 LAST BOM_COST MEM
J 0
(2725 780);
PAINT ORANGE (2725 780);
DISPLAY INVISIBLE (2725 780);
FORCEPROP 1 LAST BODY_TYPE PLUMBING
J 2
(2770 732);
DISPLAY 0.340426 (2770 732);
PAINT GREEN (2770 732);
DISPLAY INVISIBLE (2770 732);
FORCEPROP 1 LAST PATH I137
J 2
(2650 775);
DISPLAY 0.872340 (2650 775);
PAINT AQUA (2650 775);
DISPLAY INVISIBLE (2650 775);
FORCEPROP 2 LAST ROOM DDR4_CH_D
J 0
(2725 780);
PAINT ORANGE (2725 780);
DISPLAY INVISIBLE (2725 780);
FORCEPROP 1 LAST HDL_POWER GND
J 2
(2725 925);
DISPLAY 0.553191 (2725 925);
PAINT GREEN (2725 925);
DISPLAY INVISIBLE (2725 925);
FORCEADD SCONN288_H44441003..3
(3425 2075);
FORCEPROP 1 LAST PART_NUMBER H44441-003
J 0
(2975 725);
DISPLAY 0.617021 (2975 725);
PAINT BLUE (2975 725);
FORCEPROP 2 LASTPIN (2925 3225) $PN 2
J 2
(2915 3235);
DISPLAY 0.617021 (2915 3235);
PAINT ORANGE (2915 3235);
FORCEPROP 2 LASTPIN (2925 3175) $PN 4
J 2
(2915 3185);
DISPLAY 0.617021 (2915 3185);
PAINT ORANGE (2915 3185);
FORCEPROP 2 LASTPIN (2925 3125) $PN 6
J 2
(2915 3135);
DISPLAY 0.617021 (2915 3135);
PAINT ORANGE (2915 3135);
FORCEPROP 2 LASTPIN (2925 3075) $PN 9
J 2
(2915 3085);
DISPLAY 0.617021 (2915 3085);
PAINT ORANGE (2915 3085);
FORCEPROP 2 LASTPIN (2925 3025) $PN 11
J 2
(2915 3035);
DISPLAY 0.617021 (2915 3035);
PAINT ORANGE (2915 3035);
FORCEPROP 2 LASTPIN (2925 2975) $PN 13
J 2
(2915 2985);
DISPLAY 0.617021 (2915 2985);
PAINT ORANGE (2915 2985);
FORCEPROP 2 LASTPIN (2925 2875) $PN 17
J 2
(2915 2885);
DISPLAY 0.617021 (2915 2885);
PAINT ORANGE (2915 2885);
FORCEPROP 2 LASTPIN (2925 2825) $PN 20
J 2
(2915 2835);
DISPLAY 0.617021 (2915 2835);
PAINT ORANGE (2915 2835);
FORCEPROP 2 LASTPIN (2925 2775) $PN 22
J 2
(2915 2785);
DISPLAY 0.617021 (2915 2785);
PAINT ORANGE (2915 2785);
FORCEPROP 2 LASTPIN (2925 2725) $PN 24
J 2
(2915 2735);
DISPLAY 0.617021 (2915 2735);
PAINT ORANGE (2915 2735);
FORCEPROP 2 LASTPIN (2925 2675) $PN 26
J 2
(2915 2685);
DISPLAY 0.617021 (2915 2685);
PAINT ORANGE (2915 2685);
FORCEPROP 2 LASTPIN (2925 2625) $PN 28
J 2
(2915 2635);
DISPLAY 0.617021 (2915 2635);
PAINT ORANGE (2915 2635);
FORCEPROP 2 LASTPIN (2925 2575) $PN 31
J 2
(2915 2585);
DISPLAY 0.617021 (2915 2585);
PAINT ORANGE (2915 2585);
FORCEPROP 2 LASTPIN (2925 2525) $PN 33
J 2
(2915 2535);
DISPLAY 0.617021 (2915 2535);
PAINT ORANGE (2915 2535);
FORCEPROP 2 LASTPIN (2925 2475) $PN 35
J 2
(2915 2485);
DISPLAY 0.617021 (2915 2485);
PAINT ORANGE (2915 2485);
FORCEPROP 2 LASTPIN (2925 2425) $PN 37
J 2
(2915 2435);
DISPLAY 0.617021 (2915 2435);
PAINT ORANGE (2915 2435);
FORCEPROP 2 LASTPIN (2925 2375) $PN 39
J 2
(2915 2385);
DISPLAY 0.617021 (2915 2385);
PAINT ORANGE (2915 2385);
FORCEPROP 2 LASTPIN (2925 2325) $PN 42
J 2
(2915 2335);
DISPLAY 0.617021 (2915 2335);
PAINT ORANGE (2915 2335);
FORCEPROP 2 LASTPIN (2925 2275) $PN 44
J 2
(2915 2285);
DISPLAY 0.617021 (2915 2285);
PAINT ORANGE (2915 2285);
FORCEPROP 2 LASTPIN (2925 2225) $PN 46
J 2
(2915 2235);
DISPLAY 0.617021 (2915 2235);
PAINT ORANGE (2915 2235);
FORCEPROP 2 LASTPIN (2925 2175) $PN 48
J 2
(2915 2185);
DISPLAY 0.617021 (2915 2185);
PAINT ORANGE (2915 2185);
FORCEPROP 2 LASTPIN (2925 2125) $PN 50
J 2
(2915 2135);
DISPLAY 0.617021 (2915 2135);
PAINT ORANGE (2915 2135);
FORCEPROP 2 LASTPIN (2925 2075) $PN 53
J 2
(2915 2085);
DISPLAY 0.617021 (2915 2085);
PAINT ORANGE (2915 2085);
FORCEPROP 2 LASTPIN (2925 2025) $PN 55
J 2
(2915 2035);
DISPLAY 0.617021 (2915 2035);
PAINT ORANGE (2915 2035);
FORCEPROP 2 LASTPIN (2925 1975) $PN 57
J 2
(2915 1985);
DISPLAY 0.617021 (2915 1985);
PAINT ORANGE (2915 1985);
FORCEPROP 2 LASTPIN (2925 1925) $PN 94
J 2
(2915 1935);
DISPLAY 0.617021 (2915 1935);
PAINT ORANGE (2915 1935);
FORCEPROP 2 LASTPIN (2925 1875) $PN 96
J 2
(2915 1885);
DISPLAY 0.617021 (2915 1885);
PAINT ORANGE (2915 1885);
FORCEPROP 2 LASTPIN (2925 1825) $PN 98
J 2
(2915 1835);
DISPLAY 0.617021 (2915 1835);
PAINT ORANGE (2915 1835);
FORCEPROP 2 LASTPIN (2925 1775) $PN 101
J 2
(2915 1785);
DISPLAY 0.617021 (2915 1785);
PAINT ORANGE (2915 1785);
FORCEPROP 2 LASTPIN (2925 1725) $PN 103
J 2
(2915 1735);
DISPLAY 0.617021 (2915 1735);
PAINT ORANGE (2915 1735);
FORCEPROP 2 LASTPIN (2925 1625) $PN 107
J 2
(2915 1635);
DISPLAY 0.617021 (2915 1635);
PAINT ORANGE (2915 1635);
FORCEPROP 2 LASTPIN (2925 1575) $PN 109
J 2
(2915 1585);
DISPLAY 0.617021 (2915 1585);
PAINT ORANGE (2915 1585);
FORCEPROP 2 LASTPIN (2925 1525) $PN 112
J 2
(2915 1535);
DISPLAY 0.617021 (2915 1535);
PAINT ORANGE (2915 1535);
FORCEPROP 2 LASTPIN (2925 1475) $PN 114
J 2
(2915 1485);
DISPLAY 0.617021 (2915 1485);
PAINT ORANGE (2915 1485);
FORCEPROP 2 LASTPIN (2925 1425) $PN 116
J 2
(2915 1435);
DISPLAY 0.617021 (2915 1435);
PAINT ORANGE (2915 1435);
FORCEPROP 2 LASTPIN (2925 1375) $PN 118
J 2
(2915 1385);
DISPLAY 0.617021 (2915 1385);
PAINT ORANGE (2915 1385);
FORCEPROP 2 LASTPIN (2925 1325) $PN 120
J 2
(2915 1335);
DISPLAY 0.617021 (2915 1335);
PAINT ORANGE (2915 1335);
FORCEPROP 2 LASTPIN (2925 1275) $PN 123
J 2
(2915 1285);
DISPLAY 0.617021 (2915 1285);
PAINT ORANGE (2915 1285);
FORCEPROP 2 LASTPIN (2925 1225) $PN 125
J 2
(2915 1235);
DISPLAY 0.617021 (2915 1235);
PAINT ORANGE (2915 1235);
FORCEPROP 2 LASTPIN (2925 1175) $PN 127
J 2
(2915 1185);
DISPLAY 0.617021 (2915 1185);
PAINT ORANGE (2915 1185);
FORCEPROP 2 LASTPIN (2925 1125) $PN 129
J 2
(2915 1135);
DISPLAY 0.617021 (2915 1135);
PAINT ORANGE (2915 1135);
FORCEPROP 2 LASTPIN (2925 1075) $PN 131
J 2
(2915 1085);
DISPLAY 0.617021 (2915 1085);
PAINT ORANGE (2915 1085);
FORCEPROP 2 LASTPIN (2925 1025) $PN 134
J 2
(2915 1035);
DISPLAY 0.617021 (2915 1035);
PAINT ORANGE (2915 1035);
FORCEPROP 2 LASTPIN (2925 975) $PN 136
J 2
(2915 985);
DISPLAY 0.617021 (2915 985);
PAINT ORANGE (2915 985);
FORCEPROP 2 LASTPIN (2925 925) $PN 138
J 2
(2915 935);
DISPLAY 0.617021 (2915 935);
PAINT ORANGE (2915 935);
FORCEPROP 2 LASTPIN (3925 3225) $PN 147
J 0
(3935 3235);
DISPLAY 0.617021 (3935 3235);
PAINT ORANGE (3935 3235);
FORCEPROP 2 LASTPIN (3925 3175) $PN 149
J 0
(3935 3185);
DISPLAY 0.617021 (3935 3185);
PAINT ORANGE (3935 3185);
FORCEPROP 2 LASTPIN (3925 3125) $PN 151
J 0
(3935 3135);
DISPLAY 0.617021 (3935 3135);
PAINT ORANGE (3935 3135);
FORCEPROP 2 LASTPIN (3925 3075) $PN 154
J 0
(3935 3085);
DISPLAY 0.617021 (3935 3085);
PAINT ORANGE (3935 3085);
FORCEPROP 2 LASTPIN (3925 3025) $PN 156
J 0
(3935 3035);
DISPLAY 0.617021 (3935 3035);
PAINT ORANGE (3935 3035);
FORCEPROP 2 LASTPIN (3925 2975) $PN 158
J 0
(3935 2985);
DISPLAY 0.617021 (3935 2985);
PAINT ORANGE (3935 2985);
FORCEPROP 2 LASTPIN (3925 2925) $PN 160
J 0
(3935 2935);
DISPLAY 0.617021 (3935 2935);
PAINT ORANGE (3935 2935);
FORCEPROP 2 LASTPIN (3925 2875) $PN 162
J 0
(3935 2885);
DISPLAY 0.617021 (3935 2885);
PAINT ORANGE (3935 2885);
FORCEPROP 2 LASTPIN (3925 2825) $PN 165
J 0
(3935 2835);
DISPLAY 0.617021 (3935 2835);
PAINT ORANGE (3935 2835);
FORCEPROP 2 LASTPIN (3925 2775) $PN 167
J 0
(3935 2785);
DISPLAY 0.617021 (3935 2785);
PAINT ORANGE (3935 2785);
FORCEPROP 2 LASTPIN (3925 2725) $PN 169
J 0
(3935 2735);
DISPLAY 0.617021 (3935 2735);
PAINT ORANGE (3935 2735);
FORCEPROP 2 LASTPIN (3925 2675) $PN 171
J 0
(3935 2685);
DISPLAY 0.617021 (3935 2685);
PAINT ORANGE (3935 2685);
FORCEPROP 2 LASTPIN (3925 2625) $PN 173
J 0
(3935 2635);
DISPLAY 0.617021 (3935 2635);
PAINT ORANGE (3935 2635);
FORCEPROP 2 LASTPIN (3925 2575) $PN 176
J 0
(3935 2585);
DISPLAY 0.617021 (3935 2585);
PAINT ORANGE (3935 2585);
FORCEPROP 2 LASTPIN (3925 2475) $PN 180
J 0
(3935 2485);
DISPLAY 0.617021 (3935 2485);
PAINT ORANGE (3935 2485);
FORCEPROP 2 LASTPIN (3925 2425) $PN 182
J 0
(3935 2435);
DISPLAY 0.617021 (3935 2435);
PAINT ORANGE (3935 2435);
FORCEPROP 2 LASTPIN (3925 2375) $PN 184
J 0
(3935 2385);
DISPLAY 0.617021 (3935 2385);
PAINT ORANGE (3935 2385);
FORCEPROP 2 LASTPIN (3925 2325) $PN 187
J 0
(3935 2335);
DISPLAY 0.617021 (3935 2335);
PAINT ORANGE (3935 2335);
FORCEPROP 2 LASTPIN (3925 2275) $PN 189
J 0
(3935 2285);
DISPLAY 0.617021 (3935 2285);
PAINT ORANGE (3935 2285);
FORCEPROP 2 LASTPIN (3925 2175) $PN 193
J 0
(3935 2185);
DISPLAY 0.617021 (3935 2185);
PAINT ORANGE (3935 2185);
FORCEPROP 2 LASTPIN (3925 2125) $PN 195
J 0
(3935 2135);
DISPLAY 0.617021 (3935 2135);
PAINT ORANGE (3935 2135);
FORCEPROP 2 LASTPIN (3925 2075) $PN 198
J 0
(3935 2085);
DISPLAY 0.617021 (3935 2085);
PAINT ORANGE (3935 2085);
FORCEPROP 2 LASTPIN (3925 2025) $PN 200
J 0
(3935 2035);
DISPLAY 0.617021 (3935 2035);
PAINT ORANGE (3935 2035);
FORCEPROP 2 LASTPIN (3925 1975) $PN 202
J 0
(3935 1985);
DISPLAY 0.617021 (3935 1985);
PAINT ORANGE (3935 1985);
FORCEPROP 2 LASTPIN (3925 1925) $PN 239
J 0
(3935 1935);
DISPLAY 0.617021 (3935 1935);
PAINT ORANGE (3935 1935);
FORCEPROP 2 LASTPIN (3925 1875) $PN 241
J 0
(3935 1885);
DISPLAY 0.617021 (3935 1885);
PAINT ORANGE (3935 1885);
FORCEPROP 2 LASTPIN (3925 1825) $PN 243
J 0
(3935 1835);
DISPLAY 0.617021 (3935 1835);
PAINT ORANGE (3935 1835);
FORCEPROP 2 LASTPIN (3925 1775) $PN 246
J 0
(3935 1785);
DISPLAY 0.617021 (3935 1785);
PAINT ORANGE (3935 1785);
FORCEPROP 2 LASTPIN (3925 1725) $PN 248
J 0
(3935 1735);
DISPLAY 0.617021 (3935 1735);
PAINT ORANGE (3935 1735);
FORCEPROP 2 LASTPIN (3925 1675) $PN 250
J 0
(3935 1685);
DISPLAY 0.617021 (3935 1685);
PAINT ORANGE (3935 1685);
FORCEPROP 2 LASTPIN (3925 1625) $PN 252
J 0
(3935 1635);
DISPLAY 0.617021 (3935 1635);
PAINT ORANGE (3935 1635);
FORCEPROP 2 LASTPIN (3925 1575) $PN 254
J 0
(3935 1585);
DISPLAY 0.617021 (3935 1585);
PAINT ORANGE (3935 1585);
FORCEPROP 2 LASTPIN (3925 1525) $PN 257
J 0
(3935 1535);
DISPLAY 0.617021 (3935 1535);
PAINT ORANGE (3935 1535);
FORCEPROP 2 LASTPIN (3925 1475) $PN 259
J 0
(3935 1485);
DISPLAY 0.617021 (3935 1485);
PAINT ORANGE (3935 1485);
FORCEPROP 2 LASTPIN (3925 1425) $PN 261
J 0
(3935 1435);
DISPLAY 0.617021 (3935 1435);
PAINT ORANGE (3935 1435);
FORCEPROP 2 LASTPIN (3925 1375) $PN 263
J 0
(3935 1385);
DISPLAY 0.617021 (3935 1385);
PAINT ORANGE (3935 1385);
FORCEPROP 2 LASTPIN (3925 1325) $PN 265
J 0
(3935 1335);
DISPLAY 0.617021 (3935 1335);
PAINT ORANGE (3935 1335);
FORCEPROP 2 LASTPIN (3925 1275) $PN 268
J 0
(3935 1285);
DISPLAY 0.617021 (3935 1285);
PAINT ORANGE (3935 1285);
FORCEPROP 2 LASTPIN (3925 1225) $PN 270
J 0
(3935 1235);
DISPLAY 0.617021 (3935 1235);
PAINT ORANGE (3935 1235);
FORCEPROP 2 LASTPIN (3925 1175) $PN 272
J 0
(3935 1185);
DISPLAY 0.617021 (3935 1185);
PAINT ORANGE (3935 1185);
FORCEPROP 2 LASTPIN (3925 1125) $PN 274
J 0
(3935 1135);
DISPLAY 0.617021 (3935 1135);
PAINT ORANGE (3935 1135);
FORCEPROP 2 LASTPIN (3925 1075) $PN 276
J 0
(3935 1085);
DISPLAY 0.617021 (3935 1085);
PAINT ORANGE (3935 1085);
FORCEPROP 2 LASTPIN (3925 1025) $PN 279
J 0
(3935 1035);
DISPLAY 0.617021 (3935 1035);
PAINT ORANGE (3935 1035);
FORCEPROP 2 LASTPIN (3925 975) $PN 281
J 0
(3935 985);
DISPLAY 0.617021 (3935 985);
PAINT ORANGE (3935 985);
FORCEPROP 2 LASTPIN (3925 925) $PN 283
J 0
(3935 935);
DISPLAY 0.617021 (3935 935);
PAINT ORANGE (3935 935);
FORCEPROP 2 LASTPIN (2925 2925) $PN 15
J 2
(2915 2935);
DISPLAY 0.617021 (2915 2935);
PAINT ORANGE (2915 2935);
FORCEPROP 2 LASTPIN (3925 2225) $PN 191
J 0
(3935 2235);
DISPLAY 0.617021 (3935 2235);
PAINT ORANGE (3935 2235);
FORCEPROP 1 LAST LOCATION J9L2
J 0
(2975 3475);
DISPLAY 0.617021 (2975 3475);
PAINT AQUA (2975 3475);
FORCEPROP 1 LAST MATERIAL SCONN
J 0
(2975 3425);
DISPLAY 0.617021 (2975 3425);
PAINT SKYBLUE (2975 3425);
FORCEPROP 0 LAST BOM_SS NOPOP
J 0
(3281 3474);
DISPLAY 1.021277 (3281 3474);
PAINT BROWN (3281 3474);
DISPLAY BOTH (3281 3474);
FORCEPROP 2 LASTPIN (2925 1675) $PN 105
J 2
(2915 1685);
DISPLAY 0.617021 (2915 1685);
PAINT ORANGE (2915 1685);
FORCEPROP 2 LASTPIN (3925 2525) $PN 178
J 0
(3935 2535);
DISPLAY 0.617021 (3935 2535);
PAINT ORANGE (3935 2535);
FORCEPROP 1 LAST PACK_TYPE PIP
J 0
(2975 3525);
PAINT SKYBLUE (2975 3525);
DISPLAY INVISIBLE (2975 3525);
FORCEPROP 2 LAST BOM_COST MEM
J 0
(3425 2075);
PAINT ORANGE (3425 2075);
DISPLAY INVISIBLE (3425 2075);
FORCEPROP 2 LAST CDS_LIB mstr_sconn
J 0
(3425 2075);
PAINT ORANGE (3425 2075);
DISPLAY INVISIBLE (3425 2075);
FORCEPROP 2 LAST SEC_TYPE PIP
J 0
(2975 3525);
DISPLAY 1.021277 (2975 3525);
PAINT ORANGE (2975 3525);
DISPLAY INVISIBLE (2975 3525);
FORCEPROP 2 LAST SEC 3
J 0
(2975 3525);
DISPLAY 0.680851 (2975 3525);
PAINT MONO (2975 3525);
DISPLAY INVISIBLE (2975 3525);
FORCEPROP 2 LAST CDS_LOCATION J9L2
J 0
(2975 3475);
DISPLAY 0.617021 (2975 3475);
PAINT AQUA (2975 3475);
DISPLAY INVISIBLE (2975 3475);
FORCEPROP 1 LAST PATH I138
J 0
(3425 3425);
PAINT GREEN (3425 3425);
DISPLAY INVISIBLE (3425 3425);
FORCEPROP 2 LAST ROOM DDR4_CH_L
J 0
(3425 2075);
PAINT ORANGE (3425 2075);
DISPLAY INVISIBLE (3425 2075);
FORCEADD OFFPAGE..6
(-2225 2575);
FORCEPROP 2 LAST $XR1 85 
J 0
(-2564 2575);
DISPLAY 0.638298 (-2564 2575);
PAINT MONO (-2564 2575);
FORCEPROP 2 LAST $XR0 61 
J 0
(-2474 2575);
DISPLAY 0.638298 (-2474 2575);
PAINT MONO (-2474 2575);
FORCEPROP 2 LAST CDS_LIB mstr_standard
J 0
(-2225 2575);
DISPLAY 0.787234 (-2225 2575);
PAINT MONO (-2225 2575);
DISPLAY INVISIBLE (-2225 2575);
FORCEPROP 1 LAST OFFPAGE TRUE
J 0
(-1900 2450);
DISPLAY 0.936170 (-1900 2450);
PAINT GREEN (-1900 2450);
DISPLAY INVISIBLE (-1900 2450);
FORCEPROP 1 LAST COMMENT_BODY TRUE
J 0
(-2125 2500);
DISPLAY 0.936170 (-2125 2500);
PAINT GREEN (-2125 2500);
DISPLAY INVISIBLE (-2125 2500);
FORCEPROP 2 LAST PATH I14
J 0
(-2450 2625);
DISPLAY 1.021277 (-2450 2625);
PAINT ORANGE (-2450 2625);
DISPLAY INVISIBLE (-2450 2625);
FORCEADD TAP..6
R 2
(2325 3125);
FORCEPROP 3 LASTPIN (2275 3125) SIG_NAME M_L_DQS_DP<0>
J 0
(2285 3135);
DISPLAY 0.659574 (2285 3135);
PAINT MONO (2285 3135);
DISPLAY INVISIBLE (2285 3135);
FORCEPROP 1 LASTPIN (2275 3125) BN 0
J 2
(2325 3135);
DISPLAY 0.617021 (2325 3135);
PAINT PINK (2325 3135);
FORCEPROP 2 LAST CDS_LIB mstr_standard
J 0
(2325 3125);
DISPLAY 0.787234 (2325 3125);
PAINT MONO (2325 3125);
DISPLAY INVISIBLE (2325 3125);
FORCEPROP 1 LAST BODY_TYPE PLUMBING
J 2
(2325 3075);
DISPLAY 1.234043 (2325 3075);
PAINT GREEN (2325 3075);
DISPLAY INVISIBLE (2325 3075);
FORCEPROP 1 LAST HDL_TAP TRUE
J 2
(2000 3000);
DISPLAY 1.234043 (2000 3000);
PAINT GREEN (2000 3000);
DISPLAY INVISIBLE (2000 3000);
FORCEPROP 1 LAST PATH I142
J 2
(2327 3125);
DISPLAY 0.872340 (2327 3125);
PAINT GREEN (2327 3125);
DISPLAY INVISIBLE (2327 3125);
FORCEADD TAP..6
R 2
(2325 3225);
FORCEPROP 3 LASTPIN (2275 3225) SIG_NAME M_L_DQS_DP<1>
J 0
(2285 3235);
DISPLAY 0.659574 (2285 3235);
PAINT MONO (2285 3235);
DISPLAY INVISIBLE (2285 3235);
FORCEPROP 1 LASTPIN (2275 3225) BN 1
J 2
(2325 3235);
DISPLAY 0.617021 (2325 3235);
PAINT PINK (2325 3235);
FORCEPROP 2 LAST CDS_LIB mstr_standard
J 0
(2325 3225);
DISPLAY 0.787234 (2325 3225);
PAINT MONO (2325 3225);
DISPLAY INVISIBLE (2325 3225);
FORCEPROP 1 LAST BODY_TYPE PLUMBING
J 2
(2325 3175);
DISPLAY 1.234043 (2325 3175);
PAINT GREEN (2325 3175);
DISPLAY INVISIBLE (2325 3175);
FORCEPROP 1 LAST HDL_TAP TRUE
J 2
(2000 3100);
DISPLAY 1.234043 (2000 3100);
PAINT GREEN (2000 3100);
DISPLAY INVISIBLE (2000 3100);
FORCEPROP 1 LAST PATH I143
J 2
(2327 3225);
DISPLAY 0.872340 (2327 3225);
PAINT GREEN (2327 3225);
DISPLAY INVISIBLE (2327 3225);
FORCEADD TAP..6
R 2
(2525 3075);
FORCEPROP 3 LASTPIN (2475 3075) SIG_NAME M_L_DQS_DN<0>
J 0
(2485 3085);
DISPLAY 0.659574 (2485 3085);
PAINT MONO (2485 3085);
DISPLAY INVISIBLE (2485 3085);
FORCEPROP 1 LASTPIN (2475 3075) BN 0
J 2
(2525 3085);
DISPLAY 0.617021 (2525 3085);
PAINT PINK (2525 3085);
FORCEPROP 2 LAST CDS_LIB mstr_standard
J 0
(2525 3075);
DISPLAY 0.787234 (2525 3075);
PAINT MONO (2525 3075);
DISPLAY INVISIBLE (2525 3075);
FORCEPROP 1 LAST BODY_TYPE PLUMBING
J 2
(2525 3025);
DISPLAY 1.234043 (2525 3025);
PAINT GREEN (2525 3025);
DISPLAY INVISIBLE (2525 3025);
FORCEPROP 1 LAST HDL_TAP TRUE
J 2
(2200 2950);
DISPLAY 1.234043 (2200 2950);
PAINT GREEN (2200 2950);
DISPLAY INVISIBLE (2200 2950);
FORCEPROP 1 LAST PATH I144
J 2
(2527 3075);
DISPLAY 0.872340 (2527 3075);
PAINT GREEN (2527 3075);
DISPLAY INVISIBLE (2527 3075);
FORCEADD TAP..6
R 2
(2525 3175);
FORCEPROP 3 LASTPIN (2475 3175) SIG_NAME M_L_DQS_DN<1>
J 0
(2485 3185);
DISPLAY 0.659574 (2485 3185);
PAINT MONO (2485 3185);
DISPLAY INVISIBLE (2485 3185);
FORCEPROP 1 LASTPIN (2475 3175) BN 1
J 2
(2525 3185);
DISPLAY 0.617021 (2525 3185);
PAINT PINK (2525 3185);
FORCEPROP 2 LAST CDS_LIB mstr_standard
J 0
(2525 3175);
DISPLAY 0.787234 (2525 3175);
PAINT MONO (2525 3175);
DISPLAY INVISIBLE (2525 3175);
FORCEPROP 1 LAST BODY_TYPE PLUMBING
J 2
(2525 3125);
DISPLAY 1.234043 (2525 3125);
PAINT GREEN (2525 3125);
DISPLAY INVISIBLE (2525 3125);
FORCEPROP 1 LAST HDL_TAP TRUE
J 2
(2200 3050);
DISPLAY 1.234043 (2200 3050);
PAINT GREEN (2200 3050);
DISPLAY INVISIBLE (2200 3050);
FORCEPROP 1 LAST PATH I145
J 2
(2527 3175);
DISPLAY 0.872340 (2527 3175);
PAINT GREEN (2527 3175);
DISPLAY INVISIBLE (2527 3175);
FORCEADD TAP..6
R 2
(2325 3325);
FORCEPROP 3 LASTPIN (2275 3325) SIG_NAME M_L_DQS_DP<2>
J 0
(2285 3335);
DISPLAY 0.659574 (2285 3335);
PAINT MONO (2285 3335);
DISPLAY INVISIBLE (2285 3335);
FORCEPROP 1 LASTPIN (2275 3325) BN 2
J 2
(2325 3335);
DISPLAY 0.617021 (2325 3335);
PAINT PINK (2325 3335);
FORCEPROP 2 LAST CDS_LIB mstr_standard
J 0
(2325 3325);
DISPLAY 0.787234 (2325 3325);
PAINT MONO (2325 3325);
DISPLAY INVISIBLE (2325 3325);
FORCEPROP 1 LAST BODY_TYPE PLUMBING
J 2
(2325 3275);
DISPLAY 1.234043 (2325 3275);
PAINT GREEN (2325 3275);
DISPLAY INVISIBLE (2325 3275);
FORCEPROP 1 LAST HDL_TAP TRUE
J 2
(2000 3200);
DISPLAY 1.234043 (2000 3200);
PAINT GREEN (2000 3200);
DISPLAY INVISIBLE (2000 3200);
FORCEPROP 1 LAST PATH I146
J 2
(2327 3325);
DISPLAY 0.872340 (2327 3325);
PAINT GREEN (2327 3325);
DISPLAY INVISIBLE (2327 3325);
FORCEADD TAP..6
R 2
(2325 3425);
FORCEPROP 3 LASTPIN (2275 3425) SIG_NAME M_L_DQS_DP<3>
J 0
(2285 3435);
DISPLAY 0.659574 (2285 3435);
PAINT MONO (2285 3435);
DISPLAY INVISIBLE (2285 3435);
FORCEPROP 1 LASTPIN (2275 3425) BN 3
J 2
(2325 3435);
DISPLAY 0.617021 (2325 3435);
PAINT PINK (2325 3435);
FORCEPROP 2 LAST CDS_LIB mstr_standard
J 0
(2325 3425);
DISPLAY 0.787234 (2325 3425);
PAINT MONO (2325 3425);
DISPLAY INVISIBLE (2325 3425);
FORCEPROP 1 LAST BODY_TYPE PLUMBING
J 2
(2325 3375);
DISPLAY 1.234043 (2325 3375);
PAINT GREEN (2325 3375);
DISPLAY INVISIBLE (2325 3375);
FORCEPROP 1 LAST HDL_TAP TRUE
J 2
(2000 3300);
DISPLAY 1.234043 (2000 3300);
PAINT GREEN (2000 3300);
DISPLAY INVISIBLE (2000 3300);
FORCEPROP 1 LAST PATH I147
J 2
(2327 3425);
DISPLAY 0.872340 (2327 3425);
PAINT GREEN (2327 3425);
DISPLAY INVISIBLE (2327 3425);
FORCEADD TAP..6
R 2
(2325 3625);
FORCEPROP 3 LASTPIN (2275 3625) SIG_NAME M_L_DQS_DP<5>
J 0
(2285 3635);
DISPLAY 0.659574 (2285 3635);
PAINT MONO (2285 3635);
DISPLAY INVISIBLE (2285 3635);
FORCEPROP 1 LASTPIN (2275 3625) BN 5
J 2
(2325 3635);
DISPLAY 0.617021 (2325 3635);
PAINT PINK (2325 3635);
FORCEPROP 2 LAST CDS_LIB mstr_standard
J 0
(2325 3625);
DISPLAY 0.787234 (2325 3625);
PAINT MONO (2325 3625);
DISPLAY INVISIBLE (2325 3625);
FORCEPROP 1 LAST BODY_TYPE PLUMBING
J 2
(2325 3575);
DISPLAY 1.234043 (2325 3575);
PAINT GREEN (2325 3575);
DISPLAY INVISIBLE (2325 3575);
FORCEPROP 1 LAST HDL_TAP TRUE
J 2
(2000 3500);
DISPLAY 1.234043 (2000 3500);
PAINT GREEN (2000 3500);
DISPLAY INVISIBLE (2000 3500);
FORCEPROP 1 LAST PATH I148
J 2
(2327 3625);
DISPLAY 0.872340 (2327 3625);
PAINT GREEN (2327 3625);
DISPLAY INVISIBLE (2327 3625);
FORCEADD TAP..6
R 2
(2325 3525);
FORCEPROP 3 LASTPIN (2275 3525) SIG_NAME M_L_DQS_DP<4>
J 0
(2285 3535);
DISPLAY 0.659574 (2285 3535);
PAINT MONO (2285 3535);
DISPLAY INVISIBLE (2285 3535);
FORCEPROP 1 LASTPIN (2275 3525) BN 4
J 2
(2325 3535);
DISPLAY 0.617021 (2325 3535);
PAINT PINK (2325 3535);
FORCEPROP 2 LAST CDS_LIB mstr_standard
J 0
(2325 3525);
DISPLAY 0.787234 (2325 3525);
PAINT MONO (2325 3525);
DISPLAY INVISIBLE (2325 3525);
FORCEPROP 1 LAST BODY_TYPE PLUMBING
J 2
(2325 3475);
DISPLAY 1.234043 (2325 3475);
PAINT GREEN (2325 3475);
DISPLAY INVISIBLE (2325 3475);
FORCEPROP 1 LAST HDL_TAP TRUE
J 2
(2000 3400);
DISPLAY 1.234043 (2000 3400);
PAINT GREEN (2000 3400);
DISPLAY INVISIBLE (2000 3400);
FORCEPROP 1 LAST PATH I149
J 2
(2327 3525);
DISPLAY 0.872340 (2327 3525);
PAINT GREEN (2327 3525);
DISPLAY INVISIBLE (2327 3525);
FORCEADD OFFPAGE..1
(-2225 2525);
FORCEPROP 2 LAST $XR1 85 
J 0
(-2566 2525);
DISPLAY 0.638298 (-2566 2525);
PAINT MONO (-2566 2525);
FORCEPROP 2 LAST $XR0 61 
J 0
(-2476 2525);
DISPLAY 0.638298 (-2476 2525);
PAINT MONO (-2476 2525);
FORCEPROP 2 LAST CDS_LIB mstr_standard
J 0
(-2225 2525);
DISPLAY 0.787234 (-2225 2525);
PAINT MONO (-2225 2525);
DISPLAY INVISIBLE (-2225 2525);
FORCEPROP 1 LAST OFFPAGE TRUE
J 0
(-1900 2400);
DISPLAY 0.936170 (-1900 2400);
PAINT GREEN (-1900 2400);
DISPLAY INVISIBLE (-1900 2400);
FORCEPROP 1 LAST COMMENT_BODY TRUE
J 0
(-2100 2425);
DISPLAY 0.936170 (-2100 2425);
PAINT GREEN (-2100 2425);
DISPLAY INVISIBLE (-2100 2425);
FORCEPROP 2 LAST PATH I15
J 0
(-2475 2575);
DISPLAY 1.021277 (-2475 2575);
PAINT ORANGE (-2475 2575);
DISPLAY INVISIBLE (-2475 2575);
FORCEADD TAP..6
R 2
(2325 3725);
FORCEPROP 3 LASTPIN (2275 3725) SIG_NAME M_L_DQS_DP<6>
J 0
(2285 3735);
DISPLAY 0.659574 (2285 3735);
PAINT MONO (2285 3735);
DISPLAY INVISIBLE (2285 3735);
FORCEPROP 1 LASTPIN (2275 3725) BN 6
J 2
(2325 3735);
DISPLAY 0.617021 (2325 3735);
PAINT PINK (2325 3735);
FORCEPROP 2 LAST CDS_LIB mstr_standard
J 0
(2325 3725);
DISPLAY 0.787234 (2325 3725);
PAINT MONO (2325 3725);
DISPLAY INVISIBLE (2325 3725);
FORCEPROP 1 LAST BODY_TYPE PLUMBING
J 2
(2325 3675);
DISPLAY 1.234043 (2325 3675);
PAINT GREEN (2325 3675);
DISPLAY INVISIBLE (2325 3675);
FORCEPROP 1 LAST HDL_TAP TRUE
J 2
(2000 3600);
DISPLAY 1.234043 (2000 3600);
PAINT GREEN (2000 3600);
DISPLAY INVISIBLE (2000 3600);
FORCEPROP 1 LAST PATH I150
J 2
(2327 3725);
DISPLAY 0.872340 (2327 3725);
PAINT GREEN (2327 3725);
DISPLAY INVISIBLE (2327 3725);
FORCEADD TAP..6
R 2
(2525 3475);
FORCEPROP 3 LASTPIN (2475 3475) SIG_NAME M_L_DQS_DN<4>
J 0
(2485 3485);
DISPLAY 0.659574 (2485 3485);
PAINT MONO (2485 3485);
DISPLAY INVISIBLE (2485 3485);
FORCEPROP 1 LASTPIN (2475 3475) BN 4
J 2
(2525 3485);
DISPLAY 0.617021 (2525 3485);
PAINT PINK (2525 3485);
FORCEPROP 2 LAST CDS_LIB mstr_standard
J 0
(2525 3475);
DISPLAY 0.787234 (2525 3475);
PAINT MONO (2525 3475);
DISPLAY INVISIBLE (2525 3475);
FORCEPROP 1 LAST BODY_TYPE PLUMBING
J 2
(2525 3425);
DISPLAY 1.234043 (2525 3425);
PAINT GREEN (2525 3425);
DISPLAY INVISIBLE (2525 3425);
FORCEPROP 1 LAST HDL_TAP TRUE
J 2
(2200 3350);
DISPLAY 1.234043 (2200 3350);
PAINT GREEN (2200 3350);
DISPLAY INVISIBLE (2200 3350);
FORCEPROP 1 LAST PATH I151
J 2
(2527 3475);
DISPLAY 0.872340 (2527 3475);
PAINT GREEN (2527 3475);
DISPLAY INVISIBLE (2527 3475);
FORCEADD TAP..6
R 2
(2525 3275);
FORCEPROP 3 LASTPIN (2475 3275) SIG_NAME M_L_DQS_DN<2>
J 0
(2485 3285);
DISPLAY 0.659574 (2485 3285);
PAINT MONO (2485 3285);
DISPLAY INVISIBLE (2485 3285);
FORCEPROP 1 LASTPIN (2475 3275) BN 2
J 2
(2525 3285);
DISPLAY 0.617021 (2525 3285);
PAINT PINK (2525 3285);
FORCEPROP 2 LAST CDS_LIB mstr_standard
J 0
(2525 3275);
DISPLAY 0.787234 (2525 3275);
PAINT MONO (2525 3275);
DISPLAY INVISIBLE (2525 3275);
FORCEPROP 1 LAST BODY_TYPE PLUMBING
J 2
(2525 3225);
DISPLAY 1.234043 (2525 3225);
PAINT GREEN (2525 3225);
DISPLAY INVISIBLE (2525 3225);
FORCEPROP 1 LAST HDL_TAP TRUE
J 2
(2200 3150);
DISPLAY 1.234043 (2200 3150);
PAINT GREEN (2200 3150);
DISPLAY INVISIBLE (2200 3150);
FORCEPROP 1 LAST PATH I152
J 2
(2527 3275);
DISPLAY 0.872340 (2527 3275);
PAINT GREEN (2527 3275);
DISPLAY INVISIBLE (2527 3275);
FORCEADD TAP..6
R 2
(2525 3375);
FORCEPROP 3 LASTPIN (2475 3375) SIG_NAME M_L_DQS_DN<3>
J 0
(2485 3385);
DISPLAY 0.659574 (2485 3385);
PAINT MONO (2485 3385);
DISPLAY INVISIBLE (2485 3385);
FORCEPROP 1 LASTPIN (2475 3375) BN 3
J 2
(2525 3385);
DISPLAY 0.617021 (2525 3385);
PAINT PINK (2525 3385);
FORCEPROP 2 LAST CDS_LIB mstr_standard
J 0
(2525 3375);
DISPLAY 0.787234 (2525 3375);
PAINT MONO (2525 3375);
DISPLAY INVISIBLE (2525 3375);
FORCEPROP 1 LAST BODY_TYPE PLUMBING
J 2
(2525 3325);
DISPLAY 1.234043 (2525 3325);
PAINT GREEN (2525 3325);
DISPLAY INVISIBLE (2525 3325);
FORCEPROP 1 LAST HDL_TAP TRUE
J 2
(2200 3250);
DISPLAY 1.234043 (2200 3250);
PAINT GREEN (2200 3250);
DISPLAY INVISIBLE (2200 3250);
FORCEPROP 1 LAST PATH I153
J 2
(2527 3375);
DISPLAY 0.872340 (2527 3375);
PAINT GREEN (2527 3375);
DISPLAY INVISIBLE (2527 3375);
FORCEADD TAP..6
R 2
(2525 3675);
FORCEPROP 3 LASTPIN (2475 3675) SIG_NAME M_L_DQS_DN<6>
J 0
(2485 3685);
DISPLAY 0.659574 (2485 3685);
PAINT MONO (2485 3685);
DISPLAY INVISIBLE (2485 3685);
FORCEPROP 1 LASTPIN (2475 3675) BN 6
J 2
(2525 3685);
DISPLAY 0.617021 (2525 3685);
PAINT PINK (2525 3685);
FORCEPROP 2 LAST CDS_LIB mstr_standard
J 0
(2525 3675);
DISPLAY 0.787234 (2525 3675);
PAINT MONO (2525 3675);
DISPLAY INVISIBLE (2525 3675);
FORCEPROP 1 LAST BODY_TYPE PLUMBING
J 2
(2525 3625);
DISPLAY 1.234043 (2525 3625);
PAINT GREEN (2525 3625);
DISPLAY INVISIBLE (2525 3625);
FORCEPROP 1 LAST HDL_TAP TRUE
J 2
(2200 3550);
DISPLAY 1.234043 (2200 3550);
PAINT GREEN (2200 3550);
DISPLAY INVISIBLE (2200 3550);
FORCEPROP 1 LAST PATH I154
J 2
(2527 3675);
DISPLAY 0.872340 (2527 3675);
PAINT GREEN (2527 3675);
DISPLAY INVISIBLE (2527 3675);
FORCEADD TAP..6
R 2
(2525 3575);
FORCEPROP 3 LASTPIN (2475 3575) SIG_NAME M_L_DQS_DN<5>
J 0
(2485 3585);
DISPLAY 0.659574 (2485 3585);
PAINT MONO (2485 3585);
DISPLAY INVISIBLE (2485 3585);
FORCEPROP 1 LASTPIN (2475 3575) BN 5
J 2
(2525 3585);
DISPLAY 0.617021 (2525 3585);
PAINT PINK (2525 3585);
FORCEPROP 2 LAST CDS_LIB mstr_standard
J 0
(2525 3575);
DISPLAY 0.787234 (2525 3575);
PAINT MONO (2525 3575);
DISPLAY INVISIBLE (2525 3575);
FORCEPROP 1 LAST BODY_TYPE PLUMBING
J 2
(2525 3525);
DISPLAY 1.234043 (2525 3525);
PAINT GREEN (2525 3525);
DISPLAY INVISIBLE (2525 3525);
FORCEPROP 1 LAST HDL_TAP TRUE
J 2
(2200 3450);
DISPLAY 1.234043 (2200 3450);
PAINT GREEN (2200 3450);
DISPLAY INVISIBLE (2200 3450);
FORCEPROP 1 LAST PATH I155
J 2
(2527 3575);
DISPLAY 0.872340 (2527 3575);
PAINT GREEN (2527 3575);
DISPLAY INVISIBLE (2527 3575);
FORCEADD GND..1
R 2
(4125 775);
FORCEPROP 3 LASTPIN (4125 825) SIG_NAME GND\g
J 0
(4135 835);
DISPLAY 0.659574 (4135 835);
PAINT MONO (4135 835);
DISPLAY INVISIBLE (4135 835);
FORCEPROP 1 LAST VOLTAGE 0
J 0
(4125 775);
PAINT SKYBLUE (4125 775);
DISPLAY INVISIBLE (4125 775);
FORCEPROP 1 LAST SIZE 1B
J 2
(4050 725);
DISPLAY 1.170213 (4050 725);
PAINT GREEN (4050 725);
DISPLAY INVISIBLE (4050 725);
FORCEPROP 2 LAST CDS_LIB mstr_symbols
J 0
(4125 775);
DISPLAY 0.787234 (4125 775);
PAINT MONO (4125 775);
DISPLAY INVISIBLE (4125 775);
FORCEPROP 2 LAST BOM_COST MEM
J 0
(4125 780);
PAINT ORANGE (4125 780);
DISPLAY INVISIBLE (4125 780);
FORCEPROP 1 LAST BODY_TYPE PLUMBING
J 2
(4170 732);
DISPLAY 0.340426 (4170 732);
PAINT GREEN (4170 732);
DISPLAY INVISIBLE (4170 732);
FORCEPROP 1 LAST PATH I156
J 2
(4050 775);
DISPLAY 0.872340 (4050 775);
PAINT AQUA (4050 775);
DISPLAY INVISIBLE (4050 775);
FORCEPROP 2 LAST ROOM DDR4_CH_D
J 0
(4125 780);
PAINT ORANGE (4125 780);
DISPLAY INVISIBLE (4125 780);
FORCEPROP 1 LAST HDL_POWER GND
J 2
(4125 925);
DISPLAY 0.553191 (4125 925);
PAINT GREEN (4125 925);
DISPLAY INVISIBLE (4125 925);
FORCEADD TAP..6
R 2
(2325 3825);
FORCEPROP 3 LASTPIN (2275 3825) SIG_NAME M_L_DQS_DP<7>
J 0
(2285 3835);
DISPLAY 0.659574 (2285 3835);
PAINT MONO (2285 3835);
DISPLAY INVISIBLE (2285 3835);
FORCEPROP 1 LASTPIN (2275 3825) BN 7
J 2
(2325 3835);
DISPLAY 0.617021 (2325 3835);
PAINT PINK (2325 3835);
FORCEPROP 2 LAST CDS_LIB mstr_standard
J 0
(2325 3825);
DISPLAY 0.787234 (2325 3825);
PAINT MONO (2325 3825);
DISPLAY INVISIBLE (2325 3825);
FORCEPROP 1 LAST BODY_TYPE PLUMBING
J 2
(2325 3775);
DISPLAY 1.234043 (2325 3775);
PAINT GREEN (2325 3775);
DISPLAY INVISIBLE (2325 3775);
FORCEPROP 1 LAST HDL_TAP TRUE
J 2
(2000 3700);
DISPLAY 1.234043 (2000 3700);
PAINT GREEN (2000 3700);
DISPLAY INVISIBLE (2000 3700);
FORCEPROP 1 LAST PATH I157
J 2
(2327 3825);
DISPLAY 0.872340 (2327 3825);
PAINT GREEN (2327 3825);
DISPLAY INVISIBLE (2327 3825);
FORCEADD TAP..6
R 2
(2325 4025);
FORCEPROP 3 LASTPIN (2275 4025) SIG_NAME M_L_DQS_DP<9>
J 0
(2285 4035);
DISPLAY 0.659574 (2285 4035);
PAINT MONO (2285 4035);
DISPLAY INVISIBLE (2285 4035);
FORCEPROP 1 LASTPIN (2275 4025) BN 9
J 2
(2325 4035);
DISPLAY 0.617021 (2325 4035);
PAINT PINK (2325 4035);
FORCEPROP 2 LAST CDS_LIB mstr_standard
J 0
(2325 4025);
DISPLAY 0.787234 (2325 4025);
PAINT MONO (2325 4025);
DISPLAY INVISIBLE (2325 4025);
FORCEPROP 1 LAST BODY_TYPE PLUMBING
J 2
(2325 3975);
DISPLAY 1.234043 (2325 3975);
PAINT GREEN (2325 3975);
DISPLAY INVISIBLE (2325 3975);
FORCEPROP 1 LAST HDL_TAP TRUE
J 2
(2000 3900);
DISPLAY 1.234043 (2000 3900);
PAINT GREEN (2000 3900);
DISPLAY INVISIBLE (2000 3900);
FORCEPROP 1 LAST PATH I158
J 2
(2327 4025);
DISPLAY 0.872340 (2327 4025);
PAINT GREEN (2327 4025);
DISPLAY INVISIBLE (2327 4025);
FORCEADD TAP..6
R 2
(2325 3925);
FORCEPROP 3 LASTPIN (2275 3925) SIG_NAME M_L_DQS_DP<8>
J 0
(2285 3935);
DISPLAY 0.659574 (2285 3935);
PAINT MONO (2285 3935);
DISPLAY INVISIBLE (2285 3935);
FORCEPROP 1 LASTPIN (2275 3925) BN 8
J 2
(2325 3935);
DISPLAY 0.617021 (2325 3935);
PAINT PINK (2325 3935);
FORCEPROP 2 LAST CDS_LIB mstr_standard
J 0
(2325 3925);
DISPLAY 0.787234 (2325 3925);
PAINT MONO (2325 3925);
DISPLAY INVISIBLE (2325 3925);
FORCEPROP 1 LAST BODY_TYPE PLUMBING
J 2
(2325 3875);
DISPLAY 1.234043 (2325 3875);
PAINT GREEN (2325 3875);
DISPLAY INVISIBLE (2325 3875);
FORCEPROP 1 LAST HDL_TAP TRUE
J 2
(2000 3800);
DISPLAY 1.234043 (2000 3800);
PAINT GREEN (2000 3800);
DISPLAY INVISIBLE (2000 3800);
FORCEPROP 1 LAST PATH I159
J 2
(2327 3925);
DISPLAY 0.872340 (2327 3925);
PAINT GREEN (2327 3925);
DISPLAY INVISIBLE (2327 3925);
FORCEADD OFFPAGE..1
(-2225 2725);
FORCEPROP 2 LAST $XR1 85 
J 0
(-2566 2725);
DISPLAY 0.638298 (-2566 2725);
PAINT MONO (-2566 2725);
FORCEPROP 2 LAST $XR0 61 
J 0
(-2476 2725);
DISPLAY 0.638298 (-2476 2725);
PAINT MONO (-2476 2725);
FORCEPROP 2 LAST CDS_LIB mstr_standard
J 0
(-2225 2725);
DISPLAY 0.787234 (-2225 2725);
PAINT MONO (-2225 2725);
DISPLAY INVISIBLE (-2225 2725);
FORCEPROP 1 LAST OFFPAGE TRUE
J 0
(-1900 2600);
DISPLAY 0.936170 (-1900 2600);
PAINT GREEN (-1900 2600);
DISPLAY INVISIBLE (-1900 2600);
FORCEPROP 1 LAST COMMENT_BODY TRUE
J 0
(-2100 2625);
DISPLAY 0.936170 (-2100 2625);
PAINT GREEN (-2100 2625);
DISPLAY INVISIBLE (-2100 2625);
FORCEPROP 2 LAST PATH I16
J 0
(-2475 2775);
DISPLAY 1.021277 (-2475 2775);
PAINT ORANGE (-2475 2775);
DISPLAY INVISIBLE (-2475 2775);
FORCEADD TAP..6
R 2
(2325 4125);
FORCEPROP 3 LASTPIN (2275 4125) SIG_NAME M_L_DQS_DP<10>
J 0
(2285 4135);
DISPLAY 0.659574 (2285 4135);
PAINT MONO (2285 4135);
DISPLAY INVISIBLE (2285 4135);
FORCEPROP 1 LASTPIN (2275 4125) BN 10
J 2
(2325 4135);
DISPLAY 0.617021 (2325 4135);
PAINT PINK (2325 4135);
FORCEPROP 2 LAST CDS_LIB mstr_standard
J 0
(2325 4125);
DISPLAY 0.787234 (2325 4125);
PAINT MONO (2325 4125);
DISPLAY INVISIBLE (2325 4125);
FORCEPROP 1 LAST BODY_TYPE PLUMBING
J 2
(2325 4075);
DISPLAY 1.234043 (2325 4075);
PAINT GREEN (2325 4075);
DISPLAY INVISIBLE (2325 4075);
FORCEPROP 1 LAST HDL_TAP TRUE
J 2
(2000 4000);
DISPLAY 1.234043 (2000 4000);
PAINT GREEN (2000 4000);
DISPLAY INVISIBLE (2000 4000);
FORCEPROP 1 LAST PATH I160
J 2
(2327 4125);
DISPLAY 0.872340 (2327 4125);
PAINT GREEN (2327 4125);
DISPLAY INVISIBLE (2327 4125);
FORCEADD TAP..6
R 2
(2325 4225);
FORCEPROP 3 LASTPIN (2275 4225) SIG_NAME M_L_DQS_DP<11>
J 0
(2285 4235);
DISPLAY 0.659574 (2285 4235);
PAINT MONO (2285 4235);
DISPLAY INVISIBLE (2285 4235);
FORCEPROP 1 LASTPIN (2275 4225) BN 11
J 2
(2325 4235);
DISPLAY 0.617021 (2325 4235);
PAINT PINK (2325 4235);
FORCEPROP 2 LAST CDS_LIB mstr_standard
J 0
(2325 4225);
DISPLAY 0.787234 (2325 4225);
PAINT MONO (2325 4225);
DISPLAY INVISIBLE (2325 4225);
FORCEPROP 1 LAST BODY_TYPE PLUMBING
J 2
(2325 4175);
DISPLAY 1.234043 (2325 4175);
PAINT GREEN (2325 4175);
DISPLAY INVISIBLE (2325 4175);
FORCEPROP 1 LAST HDL_TAP TRUE
J 2
(2000 4100);
DISPLAY 1.234043 (2000 4100);
PAINT GREEN (2000 4100);
DISPLAY INVISIBLE (2000 4100);
FORCEPROP 1 LAST PATH I161
J 2
(2327 4225);
DISPLAY 0.872340 (2327 4225);
PAINT GREEN (2327 4225);
DISPLAY INVISIBLE (2327 4225);
FORCEADD TAP..6
R 2
(2525 3975);
FORCEPROP 3 LASTPIN (2475 3975) SIG_NAME M_L_DQS_DN<9>
J 0
(2485 3985);
DISPLAY 0.659574 (2485 3985);
PAINT MONO (2485 3985);
DISPLAY INVISIBLE (2485 3985);
FORCEPROP 1 LASTPIN (2475 3975) BN 9
J 2
(2525 3985);
DISPLAY 0.617021 (2525 3985);
PAINT PINK (2525 3985);
FORCEPROP 2 LAST CDS_LIB mstr_standard
J 0
(2525 3975);
DISPLAY 0.787234 (2525 3975);
PAINT MONO (2525 3975);
DISPLAY INVISIBLE (2525 3975);
FORCEPROP 1 LAST BODY_TYPE PLUMBING
J 2
(2525 3925);
DISPLAY 1.234043 (2525 3925);
PAINT GREEN (2525 3925);
DISPLAY INVISIBLE (2525 3925);
FORCEPROP 1 LAST HDL_TAP TRUE
J 2
(2200 3850);
DISPLAY 1.234043 (2200 3850);
PAINT GREEN (2200 3850);
DISPLAY INVISIBLE (2200 3850);
FORCEPROP 1 LAST PATH I162
J 2
(2527 3975);
DISPLAY 0.872340 (2527 3975);
PAINT GREEN (2527 3975);
DISPLAY INVISIBLE (2527 3975);
FORCEADD TAP..6
R 2
(2525 3775);
FORCEPROP 3 LASTPIN (2475 3775) SIG_NAME M_L_DQS_DN<7>
J 0
(2485 3785);
DISPLAY 0.659574 (2485 3785);
PAINT MONO (2485 3785);
DISPLAY INVISIBLE (2485 3785);
FORCEPROP 1 LASTPIN (2475 3775) BN 7
J 2
(2525 3785);
DISPLAY 0.617021 (2525 3785);
PAINT PINK (2525 3785);
FORCEPROP 2 LAST CDS_LIB mstr_standard
J 0
(2525 3775);
DISPLAY 0.787234 (2525 3775);
PAINT MONO (2525 3775);
DISPLAY INVISIBLE (2525 3775);
FORCEPROP 1 LAST BODY_TYPE PLUMBING
J 2
(2525 3725);
DISPLAY 1.234043 (2525 3725);
PAINT GREEN (2525 3725);
DISPLAY INVISIBLE (2525 3725);
FORCEPROP 1 LAST HDL_TAP TRUE
J 2
(2200 3650);
DISPLAY 1.234043 (2200 3650);
PAINT GREEN (2200 3650);
DISPLAY INVISIBLE (2200 3650);
FORCEPROP 1 LAST PATH I163
J 2
(2527 3775);
DISPLAY 0.872340 (2527 3775);
PAINT GREEN (2527 3775);
DISPLAY INVISIBLE (2527 3775);
FORCEADD TAP..6
R 2
(2525 3875);
FORCEPROP 3 LASTPIN (2475 3875) SIG_NAME M_L_DQS_DN<8>
J 0
(2485 3885);
DISPLAY 0.659574 (2485 3885);
PAINT MONO (2485 3885);
DISPLAY INVISIBLE (2485 3885);
FORCEPROP 1 LASTPIN (2475 3875) BN 8
J 2
(2525 3885);
DISPLAY 0.617021 (2525 3885);
PAINT PINK (2525 3885);
FORCEPROP 2 LAST CDS_LIB mstr_standard
J 0
(2525 3875);
DISPLAY 0.787234 (2525 3875);
PAINT MONO (2525 3875);
DISPLAY INVISIBLE (2525 3875);
FORCEPROP 1 LAST BODY_TYPE PLUMBING
J 2
(2525 3825);
DISPLAY 1.234043 (2525 3825);
PAINT GREEN (2525 3825);
DISPLAY INVISIBLE (2525 3825);
FORCEPROP 1 LAST HDL_TAP TRUE
J 2
(2200 3750);
DISPLAY 1.234043 (2200 3750);
PAINT GREEN (2200 3750);
DISPLAY INVISIBLE (2200 3750);
FORCEPROP 1 LAST PATH I164
J 2
(2527 3875);
DISPLAY 0.872340 (2527 3875);
PAINT GREEN (2527 3875);
DISPLAY INVISIBLE (2527 3875);
FORCEADD TAP..6
R 2
(2525 4175);
FORCEPROP 3 LASTPIN (2475 4175) SIG_NAME M_L_DQS_DN<11>
J 0
(2485 4185);
DISPLAY 0.659574 (2485 4185);
PAINT MONO (2485 4185);
DISPLAY INVISIBLE (2485 4185);
FORCEPROP 1 LASTPIN (2475 4175) BN 11
J 2
(2525 4185);
DISPLAY 0.617021 (2525 4185);
PAINT PINK (2525 4185);
FORCEPROP 2 LAST CDS_LIB mstr_standard
J 0
(2525 4175);
DISPLAY 0.787234 (2525 4175);
PAINT MONO (2525 4175);
DISPLAY INVISIBLE (2525 4175);
FORCEPROP 1 LAST BODY_TYPE PLUMBING
J 2
(2525 4125);
DISPLAY 1.234043 (2525 4125);
PAINT GREEN (2525 4125);
DISPLAY INVISIBLE (2525 4125);
FORCEPROP 1 LAST HDL_TAP TRUE
J 2
(2200 4050);
DISPLAY 1.234043 (2200 4050);
PAINT GREEN (2200 4050);
DISPLAY INVISIBLE (2200 4050);
FORCEPROP 1 LAST PATH I165
J 2
(2527 4175);
DISPLAY 0.872340 (2527 4175);
PAINT GREEN (2527 4175);
DISPLAY INVISIBLE (2527 4175);
FORCEADD TAP..6
R 2
(2525 4075);
FORCEPROP 3 LASTPIN (2475 4075) SIG_NAME M_L_DQS_DN<10>
J 0
(2485 4085);
DISPLAY 0.659574 (2485 4085);
PAINT MONO (2485 4085);
DISPLAY INVISIBLE (2485 4085);
FORCEPROP 1 LASTPIN (2475 4075) BN 10
J 2
(2525 4085);
DISPLAY 0.617021 (2525 4085);
PAINT PINK (2525 4085);
FORCEPROP 2 LAST CDS_LIB mstr_standard
J 0
(2525 4075);
DISPLAY 0.787234 (2525 4075);
PAINT MONO (2525 4075);
DISPLAY INVISIBLE (2525 4075);
FORCEPROP 1 LAST BODY_TYPE PLUMBING
J 2
(2525 4025);
DISPLAY 1.234043 (2525 4025);
PAINT GREEN (2525 4025);
DISPLAY INVISIBLE (2525 4025);
FORCEPROP 1 LAST HDL_TAP TRUE
J 2
(2200 3950);
DISPLAY 1.234043 (2200 3950);
PAINT GREEN (2200 3950);
DISPLAY INVISIBLE (2200 3950);
FORCEPROP 1 LAST PATH I166
J 2
(2527 4075);
DISPLAY 0.872340 (2527 4075);
PAINT GREEN (2527 4075);
DISPLAY INVISIBLE (2527 4075);
FORCEADD TAP..6
R 2
(2525 4275);
FORCEPROP 3 LASTPIN (2475 4275) SIG_NAME M_L_DQS_DN<12>
J 0
(2485 4285);
DISPLAY 0.659574 (2485 4285);
PAINT MONO (2485 4285);
DISPLAY INVISIBLE (2485 4285);
FORCEPROP 1 LASTPIN (2475 4275) BN 12
J 2
(2525 4285);
DISPLAY 0.617021 (2525 4285);
PAINT PINK (2525 4285);
FORCEPROP 2 LAST CDS_LIB mstr_standard
J 0
(2525 4275);
DISPLAY 0.787234 (2525 4275);
PAINT MONO (2525 4275);
DISPLAY INVISIBLE (2525 4275);
FORCEPROP 1 LAST BODY_TYPE PLUMBING
J 2
(2525 4225);
DISPLAY 1.234043 (2525 4225);
PAINT GREEN (2525 4225);
DISPLAY INVISIBLE (2525 4225);
FORCEPROP 1 LAST HDL_TAP TRUE
J 2
(2200 4150);
DISPLAY 1.234043 (2200 4150);
PAINT GREEN (2200 4150);
DISPLAY INVISIBLE (2200 4150);
FORCEPROP 1 LAST PATH I167
J 2
(2527 4275);
DISPLAY 0.872340 (2527 4275);
PAINT GREEN (2527 4275);
DISPLAY INVISIBLE (2527 4275);
FORCEADD TAP..6
R 2
(2325 4325);
FORCEPROP 3 LASTPIN (2275 4325) SIG_NAME M_L_DQS_DP<12>
J 0
(2285 4335);
DISPLAY 0.659574 (2285 4335);
PAINT MONO (2285 4335);
DISPLAY INVISIBLE (2285 4335);
FORCEPROP 1 LASTPIN (2275 4325) BN 12
J 2
(2325 4335);
DISPLAY 0.617021 (2325 4335);
PAINT PINK (2325 4335);
FORCEPROP 2 LAST CDS_LIB mstr_standard
J 0
(2325 4325);
DISPLAY 0.787234 (2325 4325);
PAINT MONO (2325 4325);
DISPLAY INVISIBLE (2325 4325);
FORCEPROP 1 LAST BODY_TYPE PLUMBING
J 2
(2325 4275);
DISPLAY 1.234043 (2325 4275);
PAINT GREEN (2325 4275);
DISPLAY INVISIBLE (2325 4275);
FORCEPROP 1 LAST HDL_TAP TRUE
J 2
(2000 4200);
DISPLAY 1.234043 (2000 4200);
PAINT GREEN (2000 4200);
DISPLAY INVISIBLE (2000 4200);
FORCEPROP 1 LAST PATH I168
J 2
(2327 4325);
DISPLAY 0.872340 (2327 4325);
PAINT GREEN (2327 4325);
DISPLAY INVISIBLE (2327 4325);
FORCEADD TAP..6
R 2
(2325 4525);
FORCEPROP 3 LASTPIN (2275 4525) SIG_NAME M_L_DQS_DP<14>
J 0
(2285 4535);
DISPLAY 0.659574 (2285 4535);
PAINT MONO (2285 4535);
DISPLAY INVISIBLE (2285 4535);
FORCEPROP 1 LASTPIN (2275 4525) BN 14
J 2
(2325 4535);
DISPLAY 0.617021 (2325 4535);
PAINT PINK (2325 4535);
FORCEPROP 2 LAST CDS_LIB mstr_standard
J 0
(2325 4525);
DISPLAY 0.787234 (2325 4525);
PAINT MONO (2325 4525);
DISPLAY INVISIBLE (2325 4525);
FORCEPROP 1 LAST BODY_TYPE PLUMBING
J 2
(2325 4475);
DISPLAY 1.234043 (2325 4475);
PAINT GREEN (2325 4475);
DISPLAY INVISIBLE (2325 4475);
FORCEPROP 1 LAST HDL_TAP TRUE
J 2
(2000 4400);
DISPLAY 1.234043 (2000 4400);
PAINT GREEN (2000 4400);
DISPLAY INVISIBLE (2000 4400);
FORCEPROP 1 LAST PATH I169
J 2
(2327 4525);
DISPLAY 0.872340 (2327 4525);
PAINT GREEN (2327 4525);
DISPLAY INVISIBLE (2327 4525);
FORCEADD TAP..6
(-1625 2225);
FORCEPROP 3 LASTPIN (-1575 2225) SIG_NAME M_L_ECC<1>
J 0
(-1565 2235);
DISPLAY 0.659574 (-1565 2235);
PAINT MONO (-1565 2235);
DISPLAY INVISIBLE (-1565 2235);
FORCEPROP 1 LASTPIN (-1575 2225) BN 1
J 0
(-1625 2235);
DISPLAY 0.617021 (-1625 2235);
PAINT PINK (-1625 2235);
FORCEPROP 2 LAST CDS_LIB mstr_standard
J 0
(-1625 2225);
DISPLAY 0.787234 (-1625 2225);
PAINT MONO (-1625 2225);
DISPLAY INVISIBLE (-1625 2225);
FORCEPROP 1 LAST BODY_TYPE PLUMBING
J 0
(-1625 2175);
DISPLAY 1.234043 (-1625 2175);
PAINT GREEN (-1625 2175);
DISPLAY INVISIBLE (-1625 2175);
FORCEPROP 1 LAST HDL_TAP TRUE
J 0
(-1300 2100);
DISPLAY 1.234043 (-1300 2100);
PAINT GREEN (-1300 2100);
DISPLAY INVISIBLE (-1300 2100);
FORCEPROP 1 LAST PATH I17
J 0
(-1627 2225);
DISPLAY 0.872340 (-1627 2225);
PAINT GREEN (-1627 2225);
DISPLAY INVISIBLE (-1627 2225);
FORCEADD TAP..6
R 2
(2325 4425);
FORCEPROP 3 LASTPIN (2275 4425) SIG_NAME M_L_DQS_DP<13>
J 0
(2285 4435);
DISPLAY 0.659574 (2285 4435);
PAINT MONO (2285 4435);
DISPLAY INVISIBLE (2285 4435);
FORCEPROP 1 LASTPIN (2275 4425) BN 13
J 2
(2325 4435);
DISPLAY 0.617021 (2325 4435);
PAINT PINK (2325 4435);
FORCEPROP 2 LAST CDS_LIB mstr_standard
J 0
(2325 4425);
DISPLAY 0.787234 (2325 4425);
PAINT MONO (2325 4425);
DISPLAY INVISIBLE (2325 4425);
FORCEPROP 1 LAST BODY_TYPE PLUMBING
J 2
(2325 4375);
DISPLAY 1.234043 (2325 4375);
PAINT GREEN (2325 4375);
DISPLAY INVISIBLE (2325 4375);
FORCEPROP 1 LAST HDL_TAP TRUE
J 2
(2000 4300);
DISPLAY 1.234043 (2000 4300);
PAINT GREEN (2000 4300);
DISPLAY INVISIBLE (2000 4300);
FORCEPROP 1 LAST PATH I170
J 2
(2327 4425);
DISPLAY 0.872340 (2327 4425);
PAINT GREEN (2327 4425);
DISPLAY INVISIBLE (2327 4425);
FORCEADD TAP..6
R 2
(2325 4625);
FORCEPROP 3 LASTPIN (2275 4625) SIG_NAME M_L_DQS_DP<15>
J 0
(2285 4635);
DISPLAY 0.659574 (2285 4635);
PAINT MONO (2285 4635);
DISPLAY INVISIBLE (2285 4635);
FORCEPROP 1 LASTPIN (2275 4625) BN 15
J 2
(2325 4635);
DISPLAY 0.617021 (2325 4635);
PAINT PINK (2325 4635);
FORCEPROP 2 LAST CDS_LIB mstr_standard
J 0
(2325 4625);
DISPLAY 0.787234 (2325 4625);
PAINT MONO (2325 4625);
DISPLAY INVISIBLE (2325 4625);
FORCEPROP 1 LAST BODY_TYPE PLUMBING
J 2
(2325 4575);
DISPLAY 1.234043 (2325 4575);
PAINT GREEN (2325 4575);
DISPLAY INVISIBLE (2325 4575);
FORCEPROP 1 LAST HDL_TAP TRUE
J 2
(2000 4500);
DISPLAY 1.234043 (2000 4500);
PAINT GREEN (2000 4500);
DISPLAY INVISIBLE (2000 4500);
FORCEPROP 1 LAST PATH I171
J 2
(2327 4625);
DISPLAY 0.872340 (2327 4625);
PAINT GREEN (2327 4625);
DISPLAY INVISIBLE (2327 4625);
FORCEADD TAP..6
R 2
(2325 4725);
FORCEPROP 3 LASTPIN (2275 4725) SIG_NAME M_L_DQS_DP<16>
J 0
(2285 4735);
DISPLAY 0.659574 (2285 4735);
PAINT MONO (2285 4735);
DISPLAY INVISIBLE (2285 4735);
FORCEPROP 1 LASTPIN (2275 4725) BN 16
J 2
(2325 4735);
DISPLAY 0.617021 (2325 4735);
PAINT PINK (2325 4735);
FORCEPROP 2 LAST CDS_LIB mstr_standard
J 0
(2325 4725);
DISPLAY 0.787234 (2325 4725);
PAINT MONO (2325 4725);
DISPLAY INVISIBLE (2325 4725);
FORCEPROP 1 LAST BODY_TYPE PLUMBING
J 2
(2325 4675);
DISPLAY 1.234043 (2325 4675);
PAINT GREEN (2325 4675);
DISPLAY INVISIBLE (2325 4675);
FORCEPROP 1 LAST HDL_TAP TRUE
J 2
(2000 4600);
DISPLAY 1.234043 (2000 4600);
PAINT GREEN (2000 4600);
DISPLAY INVISIBLE (2000 4600);
FORCEPROP 1 LAST PATH I172
J 2
(2327 4725);
DISPLAY 0.872340 (2327 4725);
PAINT GREEN (2327 4725);
DISPLAY INVISIBLE (2327 4725);
FORCEADD TAP..6
R 2
(2525 4375);
FORCEPROP 3 LASTPIN (2475 4375) SIG_NAME M_L_DQS_DN<13>
J 0
(2485 4385);
DISPLAY 0.659574 (2485 4385);
PAINT MONO (2485 4385);
DISPLAY INVISIBLE (2485 4385);
FORCEPROP 1 LASTPIN (2475 4375) BN 13
J 2
(2525 4385);
DISPLAY 0.617021 (2525 4385);
PAINT PINK (2525 4385);
FORCEPROP 2 LAST CDS_LIB mstr_standard
J 0
(2525 4375);
DISPLAY 0.787234 (2525 4375);
PAINT MONO (2525 4375);
DISPLAY INVISIBLE (2525 4375);
FORCEPROP 1 LAST BODY_TYPE PLUMBING
J 2
(2525 4325);
DISPLAY 1.234043 (2525 4325);
PAINT GREEN (2525 4325);
DISPLAY INVISIBLE (2525 4325);
FORCEPROP 1 LAST HDL_TAP TRUE
J 2
(2200 4250);
DISPLAY 1.234043 (2200 4250);
PAINT GREEN (2200 4250);
DISPLAY INVISIBLE (2200 4250);
FORCEPROP 1 LAST PATH I173
J 2
(2527 4375);
DISPLAY 0.872340 (2527 4375);
PAINT GREEN (2527 4375);
DISPLAY INVISIBLE (2527 4375);
FORCEADD TAP..6
R 2
(2525 4475);
FORCEPROP 3 LASTPIN (2475 4475) SIG_NAME M_L_DQS_DN<14>
J 0
(2485 4485);
DISPLAY 0.659574 (2485 4485);
PAINT MONO (2485 4485);
DISPLAY INVISIBLE (2485 4485);
FORCEPROP 1 LASTPIN (2475 4475) BN 14
J 2
(2525 4485);
DISPLAY 0.617021 (2525 4485);
PAINT PINK (2525 4485);
FORCEPROP 2 LAST CDS_LIB mstr_standard
J 0
(2525 4475);
DISPLAY 0.787234 (2525 4475);
PAINT MONO (2525 4475);
DISPLAY INVISIBLE (2525 4475);
FORCEPROP 1 LAST BODY_TYPE PLUMBING
J 2
(2525 4425);
DISPLAY 1.234043 (2525 4425);
PAINT GREEN (2525 4425);
DISPLAY INVISIBLE (2525 4425);
FORCEPROP 1 LAST HDL_TAP TRUE
J 2
(2200 4350);
DISPLAY 1.234043 (2200 4350);
PAINT GREEN (2200 4350);
DISPLAY INVISIBLE (2200 4350);
FORCEPROP 1 LAST PATH I174
J 2
(2527 4475);
DISPLAY 0.872340 (2527 4475);
PAINT GREEN (2527 4475);
DISPLAY INVISIBLE (2527 4475);
FORCEADD TAP..6
R 2
(2525 4775);
FORCEPROP 3 LASTPIN (2475 4775) SIG_NAME M_L_DQS_DN<17>
J 0
(2485 4785);
DISPLAY 0.659574 (2485 4785);
PAINT MONO (2485 4785);
DISPLAY INVISIBLE (2485 4785);
FORCEPROP 1 LASTPIN (2475 4775) BN 17
J 2
(2525 4785);
DISPLAY 0.617021 (2525 4785);
PAINT PINK (2525 4785);
FORCEPROP 2 LAST CDS_LIB mstr_standard
J 2
(2525 4775);
DISPLAY 0.787234 (2525 4775);
PAINT MONO (2525 4775);
DISPLAY INVISIBLE (2525 4775);
FORCEPROP 1 LAST BODY_TYPE PLUMBING
J 2
(2525 4725);
DISPLAY 1.234043 (2525 4725);
PAINT GREEN (2525 4725);
DISPLAY INVISIBLE (2525 4725);
FORCEPROP 1 LAST HDL_TAP TRUE
J 2
(2200 4650);
DISPLAY 1.234043 (2200 4650);
PAINT GREEN (2200 4650);
DISPLAY INVISIBLE (2200 4650);
FORCEPROP 1 LAST PATH I175
J 2
(2527 4775);
DISPLAY 0.872340 (2527 4775);
PAINT GREEN (2527 4775);
DISPLAY INVISIBLE (2527 4775);
FORCEADD TAP..6
R 2
(2525 4675);
FORCEPROP 3 LASTPIN (2475 4675) SIG_NAME M_L_DQS_DN<16>
J 0
(2485 4685);
DISPLAY 0.659574 (2485 4685);
PAINT MONO (2485 4685);
DISPLAY INVISIBLE (2485 4685);
FORCEPROP 1 LASTPIN (2475 4675) BN 16
J 2
(2525 4685);
DISPLAY 0.617021 (2525 4685);
PAINT PINK (2525 4685);
FORCEPROP 2 LAST CDS_LIB mstr_standard
J 0
(2525 4675);
DISPLAY 0.787234 (2525 4675);
PAINT MONO (2525 4675);
DISPLAY INVISIBLE (2525 4675);
FORCEPROP 1 LAST BODY_TYPE PLUMBING
J 2
(2525 4625);
DISPLAY 1.234043 (2525 4625);
PAINT GREEN (2525 4625);
DISPLAY INVISIBLE (2525 4625);
FORCEPROP 1 LAST HDL_TAP TRUE
J 2
(2200 4550);
DISPLAY 1.234043 (2200 4550);
PAINT GREEN (2200 4550);
DISPLAY INVISIBLE (2200 4550);
FORCEPROP 1 LAST PATH I176
J 2
(2527 4675);
DISPLAY 0.872340 (2527 4675);
PAINT GREEN (2527 4675);
DISPLAY INVISIBLE (2527 4675);
FORCEADD TAP..6
R 2
(2525 4575);
FORCEPROP 3 LASTPIN (2475 4575) SIG_NAME M_L_DQS_DN<15>
J 0
(2485 4585);
DISPLAY 0.659574 (2485 4585);
PAINT MONO (2485 4585);
DISPLAY INVISIBLE (2485 4585);
FORCEPROP 1 LASTPIN (2475 4575) BN 15
J 2
(2525 4585);
DISPLAY 0.617021 (2525 4585);
PAINT PINK (2525 4585);
FORCEPROP 2 LAST CDS_LIB mstr_standard
J 0
(2525 4575);
DISPLAY 0.787234 (2525 4575);
PAINT MONO (2525 4575);
DISPLAY INVISIBLE (2525 4575);
FORCEPROP 1 LAST BODY_TYPE PLUMBING
J 2
(2525 4525);
DISPLAY 1.234043 (2525 4525);
PAINT GREEN (2525 4525);
DISPLAY INVISIBLE (2525 4525);
FORCEPROP 1 LAST HDL_TAP TRUE
J 2
(2200 4450);
DISPLAY 1.234043 (2200 4450);
PAINT GREEN (2200 4450);
DISPLAY INVISIBLE (2200 4450);
FORCEPROP 1 LAST PATH I177
J 2
(2527 4575);
DISPLAY 0.872340 (2527 4575);
PAINT GREEN (2527 4575);
DISPLAY INVISIBLE (2527 4575);
FORCEADD TAP..6
R 2
(2325 4825);
FORCEPROP 3 LASTPIN (2275 4825) SIG_NAME M_L_DQS_DP<17>
J 0
(2285 4835);
DISPLAY 0.659574 (2285 4835);
PAINT MONO (2285 4835);
DISPLAY INVISIBLE (2285 4835);
FORCEPROP 1 LASTPIN (2275 4825) BN 17
J 2
(2325 4835);
DISPLAY 0.617021 (2325 4835);
PAINT PINK (2325 4835);
FORCEPROP 2 LAST CDS_LIB mstr_standard
J 2
(2325 4825);
DISPLAY 0.787234 (2325 4825);
PAINT MONO (2325 4825);
DISPLAY INVISIBLE (2325 4825);
FORCEPROP 1 LAST BODY_TYPE PLUMBING
J 2
(2325 4775);
DISPLAY 1.234043 (2325 4775);
PAINT GREEN (2325 4775);
DISPLAY INVISIBLE (2325 4775);
FORCEPROP 1 LAST HDL_TAP TRUE
J 2
(2000 4700);
DISPLAY 1.234043 (2000 4700);
PAINT GREEN (2000 4700);
DISPLAY INVISIBLE (2000 4700);
FORCEPROP 1 LAST PATH I178
J 2
(2327 4825);
DISPLAY 0.872340 (2327 4825);
PAINT GREEN (2327 4825);
DISPLAY INVISIBLE (2327 4825);
FORCEADD OFFPAGE..3
(3225 4825);
FORCEPROP 2 LAST $XR1 85 
J 0
(3529 4825);
DISPLAY 0.638298 (3529 4825);
PAINT MONO (3529 4825);
FORCEPROP 2 LAST $XR0 61 
J 0
(3439 4825);
DISPLAY 0.638298 (3439 4825);
PAINT MONO (3439 4825);
FORCEPROP 2 LAST CDS_LIB mstr_standard
J 0
(3225 4825);
DISPLAY 0.787234 (3225 4825);
PAINT MONO (3225 4825);
DISPLAY INVISIBLE (3225 4825);
FORCEPROP 1 LAST OFFPAGE TRUE
J 0
(3550 4700);
DISPLAY 0.936170 (3550 4700);
PAINT GREEN (3550 4700);
DISPLAY INVISIBLE (3550 4700);
FORCEPROP 1 LAST COMMENT_BODY TRUE
J 0
(3175 4725);
DISPLAY 0.936170 (3175 4725);
PAINT GREEN (3175 4725);
DISPLAY INVISIBLE (3175 4725);
FORCEPROP 2 LAST PATH I179
J 0
(3450 4875);
DISPLAY 1.021277 (3450 4875);
PAINT ORANGE (3450 4875);
DISPLAY INVISIBLE (3450 4875);
FORCEADD TAP..6
(-1625 2175);
FORCEPROP 3 LASTPIN (-1575 2175) SIG_NAME M_L_ECC<0>
J 0
(-1565 2185);
DISPLAY 0.659574 (-1565 2185);
PAINT MONO (-1565 2185);
DISPLAY INVISIBLE (-1565 2185);
FORCEPROP 1 LASTPIN (-1575 2175) BN 0
J 0
(-1625 2185);
DISPLAY 0.617021 (-1625 2185);
PAINT PINK (-1625 2185);
FORCEPROP 2 LAST CDS_LIB mstr_standard
J 0
(-1625 2175);
DISPLAY 0.787234 (-1625 2175);
PAINT MONO (-1625 2175);
DISPLAY INVISIBLE (-1625 2175);
FORCEPROP 1 LAST BODY_TYPE PLUMBING
J 0
(-1625 2125);
DISPLAY 1.234043 (-1625 2125);
PAINT GREEN (-1625 2125);
DISPLAY INVISIBLE (-1625 2125);
FORCEPROP 1 LAST HDL_TAP TRUE
J 0
(-1300 2050);
DISPLAY 1.234043 (-1300 2050);
PAINT GREEN (-1300 2050);
DISPLAY INVISIBLE (-1300 2050);
FORCEPROP 1 LAST PATH I18
J 0
(-1627 2175);
DISPLAY 0.872340 (-1627 2175);
PAINT GREEN (-1627 2175);
DISPLAY INVISIBLE (-1627 2175);
FORCEADD OFFPAGE..3
(3225 4875);
FORCEPROP 2 LAST $XR1 85 
J 0
(3529 4875);
DISPLAY 0.638298 (3529 4875);
PAINT MONO (3529 4875);
FORCEPROP 2 LAST $XR0 61 
J 0
(3439 4875);
DISPLAY 0.638298 (3439 4875);
PAINT MONO (3439 4875);
FORCEPROP 2 LAST CDS_LIB mstr_standard
J 0
(3225 4875);
DISPLAY 0.787234 (3225 4875);
PAINT MONO (3225 4875);
DISPLAY INVISIBLE (3225 4875);
FORCEPROP 1 LAST OFFPAGE TRUE
J 0
(3550 4750);
DISPLAY 0.936170 (3550 4750);
PAINT GREEN (3550 4750);
DISPLAY INVISIBLE (3550 4750);
FORCEPROP 1 LAST COMMENT_BODY TRUE
J 0
(3175 4775);
DISPLAY 0.936170 (3175 4775);
PAINT GREEN (3175 4775);
DISPLAY INVISIBLE (3175 4775);
FORCEPROP 2 LAST PATH I180
J 0
(3450 4925);
DISPLAY 1.021277 (3450 4925);
PAINT ORANGE (3450 4925);
DISPLAY INVISIBLE (3450 4925);
FORCEADD P12V_NVDIMM_KLM..1
(2000 2700);
FORCEPROP 3 LASTPIN (2000 2650) SIG_NAME P12V_NVDIMM_KLM\g
J 0
(2010 2660);
DISPLAY 0.659574 (2010 2660);
PAINT MONO (2010 2660);
DISPLAY INVISIBLE (2010 2660);
FORCEPROP 1 LAST VOLTAGE 12.0
J 0
(1955 2657);
DISPLAY 0.340426 (1955 2657);
PAINT SKYBLUE (1955 2657);
DISPLAY INVISIBLE (1955 2657);
FORCEPROP 2 LAST CDS_LIB mstr_symbols
J 0
(2000 2700);
PAINT ORANGE (2000 2700);
DISPLAY INVISIBLE (2000 2700);
FORCEPROP 1 LAST BODY_TYPE PLUMBING
J 0
(1955 2657);
DISPLAY 0.340426 (1955 2657);
PAINT GREEN (1955 2657);
DISPLAY INVISIBLE (1955 2657);
FORCEPROP 1 LAST PATH I181
J 0
(2050 2725);
DISPLAY 0.872340 (2050 2725);
PAINT AQUA (2050 2725);
DISPLAY INVISIBLE (2050 2725);
FORCEPROP 1 LAST HDL_POWER P12V_NVDIMM_KLM
J 1
(2000 2750);
DISPLAY 0.872340 (2000 2750);
PAINT GREEN (2000 2750);
DISPLAY INVISIBLE (2000 2750);
FORCEADD CAP_A..1
R 2
(-3025 1225);
FORCEPROP 1 LAST LOCATION C1A17
J 2
(-3075 1325);
DISPLAY 0.617021 (-3075 1325);
PAINT AQUA (-3075 1325);
FORCEPROP 1 LAST PART_NUMBER A36096-045
J 2
(-3075 1075);
DISPLAY 0.617021 (-3075 1075);
PAINT BLUE (-3075 1075);
FORCEPROP 1 LAST VALUE 0.01UF
J 2
(-3075 1275);
DISPLAY 0.617021 (-3075 1275);
PAINT SKYBLUE (-3075 1275);
FORCEPROP 1 LAST TOLERANCE 10%
J 2
(-3075 1175);
DISPLAY 0.617021 (-3075 1175);
PAINT SKYBLUE (-3075 1175);
FORCEPROP 1 LAST PACK_TYPE 0402V
J 2
(-3075 1025);
DISPLAY 0.617021 (-3075 1025);
PAINT SKYBLUE (-3075 1025);
FORCEPROP 1 LAST VOLTAGE 25V
J 2
(-3075 1225);
DISPLAY 0.617021 (-3075 1225);
PAINT SKYBLUE (-3075 1225);
FORCEPROP 1 LAST MATERIAL X7R
J 2
(-3075 1125);
DISPLAY 0.617021 (-3075 1125);
PAINT SKYBLUE (-3075 1125);
FORCEPROP 2 LAST CDS_LOCATION C1A17
J 2
(-3075 1325);
DISPLAY 0.617021 (-3075 1325);
PAINT AQUA (-3075 1325);
DISPLAY INVISIBLE (-3075 1325);
FORCEPROP 0 LAST BOM_COST MEM
J 2
(-3075 1425);
DISPLAY 1.021277 (-3075 1425);
PAINT ORANGE (-3075 1425);
DISPLAY INVISIBLE (-3075 1425);
FORCEPROP 2 LAST CDS_LIB dev_discrete
J 0
(-3025 1225);
PAINT ORANGE (-3025 1225);
DISPLAY INVISIBLE (-3025 1225);
FORCEPROP 2 LAST CDS_SEC 1
J 0
(-3075 1425);
DISPLAY 1.021277 (-3075 1425);
PAINT ORANGE (-3075 1425);
DISPLAY INVISIBLE (-3075 1425);
FORCEPROP 2 LAST $SEC 1
J 0
(-3075 1425);
DISPLAY 0.680851 (-3075 1425);
PAINT MONO (-3075 1425);
DISPLAY INVISIBLE (-3075 1425);
FORCEPROP 1 LAST PATH I182
J 2
(-3075 1375);
DISPLAY 0.978723 (-3075 1375);
PAINT WHITE (-3075 1375);
DISPLAY INVISIBLE (-3075 1375);
FORCEPROP 0 LAST ROOM DDR4_CH_D
J 2
(-3075 1425);
DISPLAY 1.021277 (-3075 1425);
PAINT ORANGE (-3075 1425);
DISPLAY INVISIBLE (-3075 1425);
FORCEPROP 1 LASTPIN (-3025 1325) $PN 1
J 2
(-3035 1305);
DISPLAY 0.787234 (-3035 1305);
PAINT ORANGE (-3035 1305);
DISPLAY INVISIBLE (-3035 1305);
FORCEPROP 1 LASTPIN (-3025 1125) $PN 2
J 2
(-3035 1105);
DISPLAY 0.787234 (-3035 1105);
PAINT ORANGE (-3035 1105);
DISPLAY INVISIBLE (-3035 1105);
FORCEADD TAP..6
(-1625 2325);
FORCEPROP 3 LASTPIN (-1575 2325) SIG_NAME M_L_ECC<3>
J 0
(-1565 2335);
DISPLAY 0.659574 (-1565 2335);
PAINT MONO (-1565 2335);
DISPLAY INVISIBLE (-1565 2335);
FORCEPROP 1 LASTPIN (-1575 2325) BN 3
J 0
(-1625 2335);
DISPLAY 0.617021 (-1625 2335);
PAINT PINK (-1625 2335);
FORCEPROP 2 LAST CDS_LIB mstr_standard
J 0
(-1625 2325);
DISPLAY 0.787234 (-1625 2325);
PAINT MONO (-1625 2325);
DISPLAY INVISIBLE (-1625 2325);
FORCEPROP 1 LAST BODY_TYPE PLUMBING
J 0
(-1625 2275);
DISPLAY 1.234043 (-1625 2275);
PAINT GREEN (-1625 2275);
DISPLAY INVISIBLE (-1625 2275);
FORCEPROP 1 LAST HDL_TAP TRUE
J 0
(-1300 2200);
DISPLAY 1.234043 (-1300 2200);
PAINT GREEN (-1300 2200);
DISPLAY INVISIBLE (-1300 2200);
FORCEPROP 1 LAST PATH I19
J 0
(-1627 2325);
DISPLAY 0.872340 (-1627 2325);
PAINT GREEN (-1627 2325);
DISPLAY INVISIBLE (-1627 2325);
FORCEADD GND..1
(-3025 975);
FORCEPROP 3 LASTPIN (-3025 1025) SIG_NAME GND\g
J 0
(-3015 1035);
DISPLAY 0.659574 (-3015 1035);
PAINT MONO (-3015 1035);
DISPLAY INVISIBLE (-3015 1035);
FORCEPROP 1 LAST VOLTAGE 0
J 0
(-3025 975);
PAINT SKYBLUE (-3025 975);
DISPLAY INVISIBLE (-3025 975);
FORCEPROP 1 LAST SIZE 1B
J 0
(-2950 925);
DISPLAY 1.787234 (-2950 925);
PAINT GREEN (-2950 925);
DISPLAY INVISIBLE (-2950 925);
FORCEPROP 2 LAST CDS_LIB mstr_symbols
J 0
(-3025 975);
PAINT ORANGE (-3025 975);
DISPLAY INVISIBLE (-3025 975);
FORCEPROP 2 LAST BOM_COST MEM
J 0
(-3025 980);
PAINT ORANGE (-3025 980);
DISPLAY INVISIBLE (-3025 980);
FORCEPROP 1 LAST BODY_TYPE PLUMBING
J 0
(-3070 932);
DISPLAY 0.340426 (-3070 932);
PAINT GREEN (-3070 932);
DISPLAY INVISIBLE (-3070 932);
FORCEPROP 1 LAST PATH I2
J 0
(-2950 975);
DISPLAY 0.872340 (-2950 975);
PAINT AQUA (-2950 975);
DISPLAY INVISIBLE (-2950 975);
FORCEPROP 2 LAST ROOM DDR4_CH_D
J 0
(-3025 980);
PAINT ORANGE (-3025 980);
DISPLAY INVISIBLE (-3025 980);
FORCEPROP 1 LAST HDL_POWER GND
J 0
(-3025 1125);
DISPLAY 1.404255 (-3025 1125);
PAINT GREEN (-3025 1125);
DISPLAY INVISIBLE (-3025 1125);
FORCEADD TAP..6
(-1625 2275);
FORCEPROP 3 LASTPIN (-1575 2275) SIG_NAME M_L_ECC<2>
J 0
(-1565 2285);
DISPLAY 0.659574 (-1565 2285);
PAINT MONO (-1565 2285);
DISPLAY INVISIBLE (-1565 2285);
FORCEPROP 1 LASTPIN (-1575 2275) BN 2
J 0
(-1625 2285);
DISPLAY 0.617021 (-1625 2285);
PAINT PINK (-1625 2285);
FORCEPROP 2 LAST CDS_LIB mstr_standard
J 0
(-1625 2275);
DISPLAY 0.787234 (-1625 2275);
PAINT MONO (-1625 2275);
DISPLAY INVISIBLE (-1625 2275);
FORCEPROP 1 LAST BODY_TYPE PLUMBING
J 0
(-1625 2225);
DISPLAY 1.234043 (-1625 2225);
PAINT GREEN (-1625 2225);
DISPLAY INVISIBLE (-1625 2225);
FORCEPROP 1 LAST HDL_TAP TRUE
J 0
(-1300 2150);
DISPLAY 1.234043 (-1300 2150);
PAINT GREEN (-1300 2150);
DISPLAY INVISIBLE (-1300 2150);
FORCEPROP 1 LAST PATH I20
J 0
(-1627 2275);
DISPLAY 0.872340 (-1627 2275);
PAINT GREEN (-1627 2275);
DISPLAY INVISIBLE (-1627 2275);
FORCEADD TAP..6
(-1625 2375);
FORCEPROP 3 LASTPIN (-1575 2375) SIG_NAME M_L_ECC<4>
J 0
(-1565 2385);
DISPLAY 0.659574 (-1565 2385);
PAINT MONO (-1565 2385);
DISPLAY INVISIBLE (-1565 2385);
FORCEPROP 1 LASTPIN (-1575 2375) BN 4
J 0
(-1625 2385);
DISPLAY 0.617021 (-1625 2385);
PAINT PINK (-1625 2385);
FORCEPROP 2 LAST CDS_LIB mstr_standard
J 0
(-1625 2375);
DISPLAY 0.787234 (-1625 2375);
PAINT MONO (-1625 2375);
DISPLAY INVISIBLE (-1625 2375);
FORCEPROP 1 LAST BODY_TYPE PLUMBING
J 0
(-1625 2325);
DISPLAY 1.234043 (-1625 2325);
PAINT GREEN (-1625 2325);
DISPLAY INVISIBLE (-1625 2325);
FORCEPROP 1 LAST HDL_TAP TRUE
J 0
(-1300 2250);
DISPLAY 1.234043 (-1300 2250);
PAINT GREEN (-1300 2250);
DISPLAY INVISIBLE (-1300 2250);
FORCEPROP 1 LAST PATH I21
J 0
(-1627 2375);
DISPLAY 0.872340 (-1627 2375);
PAINT GREEN (-1627 2375);
DISPLAY INVISIBLE (-1627 2375);
FORCEADD TAP..6
(-1625 2425);
FORCEPROP 3 LASTPIN (-1575 2425) SIG_NAME M_L_ECC<5>
J 0
(-1565 2435);
DISPLAY 0.659574 (-1565 2435);
PAINT MONO (-1565 2435);
DISPLAY INVISIBLE (-1565 2435);
FORCEPROP 1 LASTPIN (-1575 2425) BN 5
J 0
(-1625 2435);
DISPLAY 0.617021 (-1625 2435);
PAINT PINK (-1625 2435);
FORCEPROP 2 LAST CDS_LIB mstr_standard
J 0
(-1625 2425);
DISPLAY 0.787234 (-1625 2425);
PAINT MONO (-1625 2425);
DISPLAY INVISIBLE (-1625 2425);
FORCEPROP 1 LAST BODY_TYPE PLUMBING
J 0
(-1625 2375);
DISPLAY 1.234043 (-1625 2375);
PAINT GREEN (-1625 2375);
DISPLAY INVISIBLE (-1625 2375);
FORCEPROP 1 LAST HDL_TAP TRUE
J 0
(-1300 2300);
DISPLAY 1.234043 (-1300 2300);
PAINT GREEN (-1300 2300);
DISPLAY INVISIBLE (-1300 2300);
FORCEPROP 1 LAST PATH I22
J 0
(-1627 2425);
DISPLAY 0.872340 (-1627 2425);
PAINT GREEN (-1627 2425);
DISPLAY INVISIBLE (-1627 2425);
FORCEADD TAP..6
(-1625 2475);
FORCEPROP 3 LASTPIN (-1575 2475) SIG_NAME M_L_ECC<6>
J 0
(-1565 2485);
DISPLAY 0.659574 (-1565 2485);
PAINT MONO (-1565 2485);
DISPLAY INVISIBLE (-1565 2485);
FORCEPROP 1 LASTPIN (-1575 2475) BN 6
J 0
(-1625 2485);
DISPLAY 0.617021 (-1625 2485);
PAINT PINK (-1625 2485);
FORCEPROP 2 LAST CDS_LIB mstr_standard
J 0
(-1625 2475);
DISPLAY 0.787234 (-1625 2475);
PAINT MONO (-1625 2475);
DISPLAY INVISIBLE (-1625 2475);
FORCEPROP 1 LAST BODY_TYPE PLUMBING
J 0
(-1625 2425);
DISPLAY 1.234043 (-1625 2425);
PAINT GREEN (-1625 2425);
DISPLAY INVISIBLE (-1625 2425);
FORCEPROP 1 LAST HDL_TAP TRUE
J 0
(-1300 2350);
DISPLAY 1.234043 (-1300 2350);
PAINT GREEN (-1300 2350);
DISPLAY INVISIBLE (-1300 2350);
FORCEPROP 1 LAST PATH I23
J 0
(-1627 2475);
DISPLAY 0.872340 (-1627 2475);
PAINT GREEN (-1627 2475);
DISPLAY INVISIBLE (-1627 2475);
FORCEADD TAP..6
(-1625 2525);
FORCEPROP 3 LASTPIN (-1575 2525) SIG_NAME M_L_ECC<7>
J 0
(-1565 2535);
DISPLAY 0.659574 (-1565 2535);
PAINT MONO (-1565 2535);
DISPLAY INVISIBLE (-1565 2535);
FORCEPROP 1 LASTPIN (-1575 2525) BN 7
J 0
(-1625 2535);
DISPLAY 0.617021 (-1625 2535);
PAINT PINK (-1625 2535);
FORCEPROP 2 LAST CDS_LIB mstr_standard
J 0
(-1625 2525);
DISPLAY 0.787234 (-1625 2525);
PAINT MONO (-1625 2525);
DISPLAY INVISIBLE (-1625 2525);
FORCEPROP 1 LAST BODY_TYPE PLUMBING
J 0
(-1625 2475);
DISPLAY 1.234043 (-1625 2475);
PAINT GREEN (-1625 2475);
DISPLAY INVISIBLE (-1625 2475);
FORCEPROP 1 LAST HDL_TAP TRUE
J 0
(-1300 2400);
DISPLAY 1.234043 (-1300 2400);
PAINT GREEN (-1300 2400);
DISPLAY INVISIBLE (-1300 2400);
FORCEPROP 1 LAST PATH I24
J 0
(-1627 2525);
DISPLAY 0.872340 (-1627 2525);
PAINT GREEN (-1627 2525);
DISPLAY INVISIBLE (-1627 2525);
FORCEADD TAP..6
(-1625 2675);
FORCEPROP 3 LASTPIN (-1575 2675) SIG_NAME M_L_ODT<3>
J 0
(-1565 2685);
DISPLAY 0.659574 (-1565 2685);
PAINT MONO (-1565 2685);
DISPLAY INVISIBLE (-1565 2685);
FORCEPROP 1 LASTPIN (-1575 2675) BN 3
J 0
(-1625 2685);
DISPLAY 0.617021 (-1625 2685);
PAINT PINK (-1625 2685);
FORCEPROP 2 LAST CDS_LIB mstr_standard
J 0
(-1625 2675);
DISPLAY 0.787234 (-1625 2675);
PAINT MONO (-1625 2675);
DISPLAY INVISIBLE (-1625 2675);
FORCEPROP 1 LAST BODY_TYPE PLUMBING
J 0
(-1625 2625);
DISPLAY 1.234043 (-1625 2625);
PAINT GREEN (-1625 2625);
DISPLAY INVISIBLE (-1625 2625);
FORCEPROP 1 LAST HDL_TAP TRUE
J 0
(-1300 2550);
DISPLAY 1.234043 (-1300 2550);
PAINT GREEN (-1300 2550);
DISPLAY INVISIBLE (-1300 2550);
FORCEPROP 1 LAST PATH I25
J 0
(-1627 2675);
DISPLAY 0.872340 (-1627 2675);
PAINT GREEN (-1627 2675);
DISPLAY INVISIBLE (-1627 2675);
FORCEADD TAP..6
(-1625 2625);
FORCEPROP 3 LASTPIN (-1575 2625) SIG_NAME M_L_ODT<2>
J 0
(-1565 2635);
DISPLAY 0.659574 (-1565 2635);
PAINT MONO (-1565 2635);
DISPLAY INVISIBLE (-1565 2635);
FORCEPROP 1 LASTPIN (-1575 2625) BN 2
J 0
(-1625 2635);
DISPLAY 0.617021 (-1625 2635);
PAINT PINK (-1625 2635);
FORCEPROP 2 LAST CDS_LIB mstr_standard
J 0
(-1625 2625);
DISPLAY 0.787234 (-1625 2625);
PAINT MONO (-1625 2625);
DISPLAY INVISIBLE (-1625 2625);
FORCEPROP 1 LAST BODY_TYPE PLUMBING
J 0
(-1625 2575);
DISPLAY 1.234043 (-1625 2575);
PAINT GREEN (-1625 2575);
DISPLAY INVISIBLE (-1625 2575);
FORCEPROP 1 LAST HDL_TAP TRUE
J 0
(-1300 2500);
DISPLAY 1.234043 (-1300 2500);
PAINT GREEN (-1300 2500);
DISPLAY INVISIBLE (-1300 2500);
FORCEPROP 1 LAST PATH I26
J 0
(-1627 2625);
DISPLAY 0.872340 (-1627 2625);
PAINT GREEN (-1627 2625);
DISPLAY INVISIBLE (-1627 2625);
FORCEADD OFFPAGE..1
(-2225 2875);
FORCEPROP 2 LAST $XR1 85 
J 0
(-2566 2875);
DISPLAY 0.638298 (-2566 2875);
PAINT MONO (-2566 2875);
FORCEPROP 2 LAST $XR0 61 
J 0
(-2476 2875);
DISPLAY 0.638298 (-2476 2875);
PAINT MONO (-2476 2875);
FORCEPROP 2 LAST CDS_LIB mstr_standard
J 0
(-2225 2875);
DISPLAY 0.787234 (-2225 2875);
PAINT MONO (-2225 2875);
DISPLAY INVISIBLE (-2225 2875);
FORCEPROP 1 LAST OFFPAGE TRUE
J 0
(-1900 2750);
DISPLAY 0.936170 (-1900 2750);
PAINT GREEN (-1900 2750);
DISPLAY INVISIBLE (-1900 2750);
FORCEPROP 1 LAST COMMENT_BODY TRUE
J 0
(-2100 2775);
DISPLAY 0.936170 (-2100 2775);
PAINT GREEN (-2100 2775);
DISPLAY INVISIBLE (-2100 2775);
FORCEPROP 2 LAST PATH I27
J 0
(-2475 2925);
DISPLAY 1.021277 (-2475 2925);
PAINT ORANGE (-2475 2925);
DISPLAY INVISIBLE (-2475 2925);
FORCEADD OFFPAGE..1
(-2225 3125);
FORCEPROP 2 LAST $XR1 85 
J 0
(-2566 3125);
DISPLAY 0.638298 (-2566 3125);
PAINT MONO (-2566 3125);
FORCEPROP 2 LAST $XR0 61 
J 0
(-2476 3125);
DISPLAY 0.638298 (-2476 3125);
PAINT MONO (-2476 3125);
FORCEPROP 2 LAST CDS_LIB mstr_standard
J 0
(-2225 3125);
DISPLAY 0.787234 (-2225 3125);
PAINT MONO (-2225 3125);
DISPLAY INVISIBLE (-2225 3125);
FORCEPROP 1 LAST OFFPAGE TRUE
J 0
(-1900 3000);
DISPLAY 0.936170 (-1900 3000);
PAINT GREEN (-1900 3000);
DISPLAY INVISIBLE (-1900 3000);
FORCEPROP 1 LAST COMMENT_BODY TRUE
J 0
(-2100 3025);
DISPLAY 0.936170 (-2100 3025);
PAINT GREEN (-2100 3025);
DISPLAY INVISIBLE (-2100 3025);
FORCEPROP 2 LAST PATH I28
J 0
(-2475 3175);
DISPLAY 1.021277 (-2475 3175);
PAINT ORANGE (-2475 3175);
DISPLAY INVISIBLE (-2475 3175);
FORCEADD OFFPAGE..1
(-2225 3175);
FORCEPROP 2 LAST $XR1 85 
J 0
(-2566 3175);
DISPLAY 0.638298 (-2566 3175);
PAINT MONO (-2566 3175);
FORCEPROP 2 LAST $XR0 61 
J 0
(-2476 3175);
DISPLAY 0.638298 (-2476 3175);
PAINT MONO (-2476 3175);
FORCEPROP 2 LAST CDS_LIB mstr_standard
J 0
(-2225 3175);
DISPLAY 0.787234 (-2225 3175);
PAINT MONO (-2225 3175);
DISPLAY INVISIBLE (-2225 3175);
FORCEPROP 1 LAST OFFPAGE TRUE
J 0
(-1900 3050);
DISPLAY 0.936170 (-1900 3050);
PAINT GREEN (-1900 3050);
DISPLAY INVISIBLE (-1900 3050);
FORCEPROP 1 LAST COMMENT_BODY TRUE
J 0
(-2100 3075);
DISPLAY 0.936170 (-2100 3075);
PAINT GREEN (-2100 3075);
DISPLAY INVISIBLE (-2100 3075);
FORCEPROP 2 LAST PATH I29
J 0
(-2475 3225);
DISPLAY 1.021277 (-2475 3225);
PAINT ORANGE (-2475 3225);
DISPLAY INVISIBLE (-2475 3225);
FORCEADD OFFPAGE..1
(-2225 3375);
FORCEPROP 2 LAST $XR1 85 
J 0
(-2566 3375);
DISPLAY 0.638298 (-2566 3375);
PAINT MONO (-2566 3375);
FORCEPROP 2 LAST $XR0 61 
J 0
(-2476 3375);
DISPLAY 0.638298 (-2476 3375);
PAINT MONO (-2476 3375);
FORCEPROP 2 LAST CDS_LIB mstr_standard
J 0
(-2225 3375);
DISPLAY 0.787234 (-2225 3375);
PAINT MONO (-2225 3375);
DISPLAY INVISIBLE (-2225 3375);
FORCEPROP 1 LAST OFFPAGE TRUE
J 0
(-1900 3250);
DISPLAY 0.936170 (-1900 3250);
PAINT GREEN (-1900 3250);
DISPLAY INVISIBLE (-1900 3250);
FORCEPROP 1 LAST COMMENT_BODY TRUE
J 0
(-2100 3275);
DISPLAY 0.936170 (-2100 3275);
PAINT GREEN (-2100 3275);
DISPLAY INVISIBLE (-2100 3275);
FORCEPROP 2 LAST PATH I30
J 0
(-2475 3425);
DISPLAY 1.021277 (-2475 3425);
PAINT ORANGE (-2475 3425);
DISPLAY INVISIBLE (-2475 3425);
FORCEADD OFFPAGE..1
(-2225 3425);
FORCEPROP 2 LAST $XR1 85 
J 0
(-2566 3425);
DISPLAY 0.638298 (-2566 3425);
PAINT MONO (-2566 3425);
FORCEPROP 2 LAST $XR0 61 
J 0
(-2476 3425);
DISPLAY 0.638298 (-2476 3425);
PAINT MONO (-2476 3425);
FORCEPROP 2 LAST CDS_LIB mstr_standard
J 0
(-2225 3425);
DISPLAY 0.787234 (-2225 3425);
PAINT MONO (-2225 3425);
DISPLAY INVISIBLE (-2225 3425);
FORCEPROP 1 LAST OFFPAGE TRUE
J 0
(-1900 3300);
DISPLAY 0.936170 (-1900 3300);
PAINT GREEN (-1900 3300);
DISPLAY INVISIBLE (-1900 3300);
FORCEPROP 1 LAST COMMENT_BODY TRUE
J 0
(-2100 3325);
DISPLAY 0.936170 (-2100 3325);
PAINT GREEN (-2100 3325);
DISPLAY INVISIBLE (-2100 3325);
FORCEPROP 2 LAST PATH I31
J 0
(-2475 3475);
DISPLAY 1.021277 (-2475 3475);
PAINT ORANGE (-2475 3475);
DISPLAY INVISIBLE (-2475 3475);
FORCEADD OFFPAGE..1
(-2225 3550);
FORCEPROP 2 LAST $XR1 85 
J 0
(-2566 3550);
DISPLAY 0.638298 (-2566 3550);
PAINT MONO (-2566 3550);
FORCEPROP 2 LAST $XR0 61 
J 0
(-2476 3550);
DISPLAY 0.638298 (-2476 3550);
PAINT MONO (-2476 3550);
FORCEPROP 2 LAST CDS_LIB mstr_standard
J 0
(-2225 3550);
DISPLAY 0.787234 (-2225 3550);
PAINT MONO (-2225 3550);
DISPLAY INVISIBLE (-2225 3550);
FORCEPROP 1 LAST OFFPAGE TRUE
J 0
(-1900 3425);
DISPLAY 0.936170 (-1900 3425);
PAINT GREEN (-1900 3425);
DISPLAY INVISIBLE (-1900 3425);
FORCEPROP 1 LAST COMMENT_BODY TRUE
J 0
(-2100 3450);
DISPLAY 0.936170 (-2100 3450);
PAINT GREEN (-2100 3450);
DISPLAY INVISIBLE (-2100 3450);
FORCEPROP 2 LAST PATH I32
J 0
(-2475 3600);
DISPLAY 1.021277 (-2475 3600);
PAINT ORANGE (-2475 3600);
DISPLAY INVISIBLE (-2475 3600);
FORCEADD OFFPAGE..1
(-2225 3675);
FORCEPROP 2 LAST $XR1 85 
J 0
(-2566 3675);
DISPLAY 0.638298 (-2566 3675);
PAINT MONO (-2566 3675);
FORCEPROP 2 LAST $XR0 61 
J 0
(-2476 3675);
DISPLAY 0.638298 (-2476 3675);
PAINT MONO (-2476 3675);
FORCEPROP 2 LAST CDS_LIB mstr_standard
J 0
(-2225 3675);
DISPLAY 0.787234 (-2225 3675);
PAINT MONO (-2225 3675);
DISPLAY INVISIBLE (-2225 3675);
FORCEPROP 1 LAST OFFPAGE TRUE
J 0
(-1900 3550);
DISPLAY 0.936170 (-1900 3550);
PAINT GREEN (-1900 3550);
DISPLAY INVISIBLE (-1900 3550);
FORCEPROP 1 LAST COMMENT_BODY TRUE
J 0
(-2100 3575);
DISPLAY 0.936170 (-2100 3575);
PAINT GREEN (-2100 3575);
DISPLAY INVISIBLE (-2100 3575);
FORCEPROP 2 LAST PATH I33
J 0
(-2475 3725);
DISPLAY 1.021277 (-2475 3725);
PAINT ORANGE (-2475 3725);
DISPLAY INVISIBLE (-2475 3725);
FORCEADD TAP..6
(-1825 3225);
FORCEPROP 3 LASTPIN (-1775 3225) SIG_NAME M_L_CLK_DN<2>
J 0
(-1765 3235);
DISPLAY 0.659574 (-1765 3235);
PAINT MONO (-1765 3235);
DISPLAY INVISIBLE (-1765 3235);
FORCEPROP 1 LASTPIN (-1775 3225) BN 2
J 0
(-1825 3235);
DISPLAY 0.617021 (-1825 3235);
PAINT PINK (-1825 3235);
FORCEPROP 2 LAST CDS_LIB mstr_standard
J 0
(-1825 3225);
DISPLAY 0.787234 (-1825 3225);
PAINT MONO (-1825 3225);
DISPLAY INVISIBLE (-1825 3225);
FORCEPROP 1 LAST BODY_TYPE PLUMBING
J 0
(-1825 3175);
DISPLAY 1.234043 (-1825 3175);
PAINT GREEN (-1825 3175);
DISPLAY INVISIBLE (-1825 3175);
FORCEPROP 1 LAST HDL_TAP TRUE
J 0
(-1500 3100);
DISPLAY 1.234043 (-1500 3100);
PAINT GREEN (-1500 3100);
DISPLAY INVISIBLE (-1500 3100);
FORCEPROP 1 LAST PATH I34
J 0
(-1827 3225);
DISPLAY 0.872340 (-1827 3225);
PAINT GREEN (-1827 3225);
DISPLAY INVISIBLE (-1827 3225);
FORCEADD TAP..6
(-1625 2825);
FORCEPROP 3 LASTPIN (-1575 2825) SIG_NAME M_L_CKE<3>
J 0
(-1565 2835);
DISPLAY 0.659574 (-1565 2835);
PAINT MONO (-1565 2835);
DISPLAY INVISIBLE (-1565 2835);
FORCEPROP 1 LASTPIN (-1575 2825) BN 3
J 0
(-1625 2835);
DISPLAY 0.617021 (-1625 2835);
PAINT PINK (-1625 2835);
FORCEPROP 2 LAST CDS_LIB mstr_standard
J 0
(-1625 2825);
DISPLAY 0.787234 (-1625 2825);
PAINT MONO (-1625 2825);
DISPLAY INVISIBLE (-1625 2825);
FORCEPROP 1 LAST BODY_TYPE PLUMBING
J 0
(-1625 2775);
DISPLAY 1.234043 (-1625 2775);
PAINT GREEN (-1625 2775);
DISPLAY INVISIBLE (-1625 2775);
FORCEPROP 1 LAST HDL_TAP TRUE
J 0
(-1300 2700);
DISPLAY 1.234043 (-1300 2700);
PAINT GREEN (-1300 2700);
DISPLAY INVISIBLE (-1300 2700);
FORCEPROP 1 LAST PATH I35
J 0
(-1627 2825);
DISPLAY 0.872340 (-1627 2825);
PAINT GREEN (-1627 2825);
DISPLAY INVISIBLE (-1627 2825);
FORCEADD TAP..6
(-1625 2775);
FORCEPROP 3 LASTPIN (-1575 2775) SIG_NAME M_L_CKE<2>
J 0
(-1565 2785);
DISPLAY 0.659574 (-1565 2785);
PAINT MONO (-1565 2785);
DISPLAY INVISIBLE (-1565 2785);
FORCEPROP 1 LASTPIN (-1575 2775) BN 2
J 0
(-1625 2785);
DISPLAY 0.617021 (-1625 2785);
PAINT PINK (-1625 2785);
FORCEPROP 2 LAST CDS_LIB mstr_standard
J 0
(-1625 2775);
DISPLAY 0.787234 (-1625 2775);
PAINT MONO (-1625 2775);
DISPLAY INVISIBLE (-1625 2775);
FORCEPROP 1 LAST BODY_TYPE PLUMBING
J 0
(-1625 2725);
DISPLAY 1.234043 (-1625 2725);
PAINT GREEN (-1625 2725);
DISPLAY INVISIBLE (-1625 2725);
FORCEPROP 1 LAST HDL_TAP TRUE
J 0
(-1300 2650);
DISPLAY 1.234043 (-1300 2650);
PAINT GREEN (-1300 2650);
DISPLAY INVISIBLE (-1300 2650);
FORCEPROP 1 LAST PATH I36
J 0
(-1627 2775);
DISPLAY 0.872340 (-1627 2775);
PAINT GREEN (-1627 2775);
DISPLAY INVISIBLE (-1627 2775);
FORCEADD TAP..6
(-1625 2975);
FORCEPROP 3 LASTPIN (-1575 2975) SIG_NAME M_L_CS_N<5>
J 0
(-1565 2985);
DISPLAY 0.659574 (-1565 2985);
PAINT MONO (-1565 2985);
DISPLAY INVISIBLE (-1565 2985);
FORCEPROP 1 LASTPIN (-1575 2975) BN 5
J 0
(-1625 2985);
DISPLAY 0.617021 (-1625 2985);
PAINT PINK (-1625 2985);
FORCEPROP 2 LAST CDS_LIB mstr_standard
J 0
(-1625 2975);
DISPLAY 0.787234 (-1625 2975);
PAINT MONO (-1625 2975);
DISPLAY INVISIBLE (-1625 2975);
FORCEPROP 1 LAST BODY_TYPE PLUMBING
J 0
(-1625 2925);
DISPLAY 1.234043 (-1625 2925);
PAINT GREEN (-1625 2925);
DISPLAY INVISIBLE (-1625 2925);
FORCEPROP 1 LAST HDL_TAP TRUE
J 0
(-1300 2850);
DISPLAY 1.234043 (-1300 2850);
PAINT GREEN (-1300 2850);
DISPLAY INVISIBLE (-1300 2850);
FORCEPROP 1 LAST PATH I37
J 0
(-1627 2975);
DISPLAY 0.872340 (-1627 2975);
PAINT GREEN (-1627 2975);
DISPLAY INVISIBLE (-1627 2975);
FORCEADD TAP..6
(-1625 2925);
FORCEPROP 3 LASTPIN (-1575 2925) SIG_NAME M_L_CS_N<4>
J 0
(-1565 2935);
DISPLAY 0.659574 (-1565 2935);
PAINT MONO (-1565 2935);
DISPLAY INVISIBLE (-1565 2935);
FORCEPROP 1 LASTPIN (-1575 2925) BN 4
J 0
(-1625 2935);
DISPLAY 0.617021 (-1625 2935);
PAINT PINK (-1625 2935);
FORCEPROP 2 LAST CDS_LIB mstr_standard
J 0
(-1625 2925);
DISPLAY 0.787234 (-1625 2925);
PAINT MONO (-1625 2925);
DISPLAY INVISIBLE (-1625 2925);
FORCEPROP 1 LAST BODY_TYPE PLUMBING
J 0
(-1625 2875);
DISPLAY 1.234043 (-1625 2875);
PAINT GREEN (-1625 2875);
DISPLAY INVISIBLE (-1625 2875);
FORCEPROP 1 LAST HDL_TAP TRUE
J 0
(-1300 2800);
DISPLAY 1.234043 (-1300 2800);
PAINT GREEN (-1300 2800);
DISPLAY INVISIBLE (-1300 2800);
FORCEPROP 1 LAST PATH I38
J 0
(-1627 2925);
DISPLAY 0.872340 (-1627 2925);
PAINT GREEN (-1627 2925);
DISPLAY INVISIBLE (-1627 2925);
FORCEADD TAP..6
(-1625 3075);
FORCEPROP 3 LASTPIN (-1575 3075) SIG_NAME M_L_CS_N<7>
J 0
(-1565 3085);
DISPLAY 0.659574 (-1565 3085);
PAINT MONO (-1565 3085);
DISPLAY INVISIBLE (-1565 3085);
FORCEPROP 1 LASTPIN (-1575 3075) BN 7
J 0
(-1625 3085);
DISPLAY 0.617021 (-1625 3085);
PAINT PINK (-1625 3085);
FORCEPROP 2 LAST CDS_LIB mstr_standard
J 0
(-1625 3075);
DISPLAY 0.787234 (-1625 3075);
PAINT MONO (-1625 3075);
DISPLAY INVISIBLE (-1625 3075);
FORCEPROP 1 LAST BODY_TYPE PLUMBING
J 0
(-1625 3025);
DISPLAY 1.234043 (-1625 3025);
PAINT GREEN (-1625 3025);
DISPLAY INVISIBLE (-1625 3025);
FORCEPROP 1 LAST HDL_TAP TRUE
J 0
(-1300 2950);
DISPLAY 1.234043 (-1300 2950);
PAINT GREEN (-1300 2950);
DISPLAY INVISIBLE (-1300 2950);
FORCEPROP 1 LAST PATH I39
J 0
(-1627 3075);
DISPLAY 0.872340 (-1627 3075);
PAINT GREEN (-1627 3075);
DISPLAY INVISIBLE (-1627 3075);
FORCEADD OFFPAGE..1
(-3175 1425);
FORCEPROP 2 LAST $XR1 85 
J 0
(-3517 1425);
DISPLAY 0.638298 (-3517 1425);
PAINT MONO (-3517 1425);
FORCEPROP 2 LAST $XR0 100 
J 0
(-3427 1425);
DISPLAY 0.638298 (-3427 1425);
PAINT MONO (-3427 1425);
FORCEPROP 2 LAST CDS_LIB mstr_standard
J 0
(-3175 1425);
DISPLAY 0.787234 (-3175 1425);
PAINT MONO (-3175 1425);
DISPLAY INVISIBLE (-3175 1425);
FORCEPROP 1 LAST OFFPAGE TRUE
J 0
(-2850 1300);
DISPLAY 0.936170 (-2850 1300);
PAINT GREEN (-2850 1300);
DISPLAY INVISIBLE (-2850 1300);
FORCEPROP 1 LAST COMMENT_BODY TRUE
J 0
(-3050 1325);
DISPLAY 0.936170 (-3050 1325);
PAINT GREEN (-3050 1325);
DISPLAY INVISIBLE (-3050 1325);
FORCEPROP 2 LAST PATH I4
J 0
(-3425 1475);
DISPLAY 1.021277 (-3425 1475);
PAINT ORANGE (-3425 1475);
DISPLAY INVISIBLE (-3425 1475);
FORCEADD TAP..6
(-1625 3025);
FORCEPROP 3 LASTPIN (-1575 3025) SIG_NAME M_L_CS_N<6>
J 0
(-1565 3035);
DISPLAY 0.659574 (-1565 3035);
PAINT MONO (-1565 3035);
DISPLAY INVISIBLE (-1565 3035);
FORCEPROP 1 LASTPIN (-1575 3025) BN 6
J 0
(-1625 3035);
DISPLAY 0.617021 (-1625 3035);
PAINT PINK (-1625 3035);
FORCEPROP 2 LAST CDS_LIB mstr_standard
J 0
(-1625 3025);
DISPLAY 0.787234 (-1625 3025);
PAINT MONO (-1625 3025);
DISPLAY INVISIBLE (-1625 3025);
FORCEPROP 1 LAST BODY_TYPE PLUMBING
J 0
(-1625 2975);
DISPLAY 1.234043 (-1625 2975);
PAINT GREEN (-1625 2975);
DISPLAY INVISIBLE (-1625 2975);
FORCEPROP 1 LAST HDL_TAP TRUE
J 0
(-1300 2900);
DISPLAY 1.234043 (-1300 2900);
PAINT GREEN (-1300 2900);
DISPLAY INVISIBLE (-1300 2900);
FORCEPROP 1 LAST PATH I40
J 0
(-1627 3025);
DISPLAY 0.872340 (-1627 3025);
PAINT GREEN (-1627 3025);
DISPLAY INVISIBLE (-1627 3025);
FORCEADD TAP..6
(-1825 3325);
FORCEPROP 3 LASTPIN (-1775 3325) SIG_NAME M_L_CLK_DN<3>
J 0
(-1765 3335);
DISPLAY 0.659574 (-1765 3335);
PAINT MONO (-1765 3335);
DISPLAY INVISIBLE (-1765 3335);
FORCEPROP 1 LASTPIN (-1775 3325) BN 3
J 0
(-1825 3335);
DISPLAY 0.617021 (-1825 3335);
PAINT PINK (-1825 3335);
FORCEPROP 2 LAST CDS_LIB mstr_standard
J 0
(-1825 3325);
DISPLAY 0.787234 (-1825 3325);
PAINT MONO (-1825 3325);
DISPLAY INVISIBLE (-1825 3325);
FORCEPROP 1 LAST BODY_TYPE PLUMBING
J 0
(-1825 3275);
DISPLAY 1.234043 (-1825 3275);
PAINT GREEN (-1825 3275);
DISPLAY INVISIBLE (-1825 3275);
FORCEPROP 1 LAST HDL_TAP TRUE
J 0
(-1500 3200);
DISPLAY 1.234043 (-1500 3200);
PAINT GREEN (-1500 3200);
DISPLAY INVISIBLE (-1500 3200);
FORCEPROP 1 LAST PATH I41
J 0
(-1827 3325);
DISPLAY 0.872340 (-1827 3325);
PAINT GREEN (-1827 3325);
DISPLAY INVISIBLE (-1827 3325);
FORCEADD TAP..6
(-1625 3275);
FORCEPROP 3 LASTPIN (-1575 3275) SIG_NAME M_L_CLK_DP<2>
J 0
(-1565 3285);
DISPLAY 0.659574 (-1565 3285);
PAINT MONO (-1565 3285);
DISPLAY INVISIBLE (-1565 3285);
FORCEPROP 1 LASTPIN (-1575 3275) BN 2
J 0
(-1625 3285);
DISPLAY 0.617021 (-1625 3285);
PAINT PINK (-1625 3285);
FORCEPROP 2 LAST CDS_LIB mstr_standard
J 0
(-1625 3275);
DISPLAY 0.787234 (-1625 3275);
PAINT MONO (-1625 3275);
DISPLAY INVISIBLE (-1625 3275);
FORCEPROP 1 LAST BODY_TYPE PLUMBING
J 0
(-1625 3225);
DISPLAY 1.234043 (-1625 3225);
PAINT GREEN (-1625 3225);
DISPLAY INVISIBLE (-1625 3225);
FORCEPROP 1 LAST HDL_TAP TRUE
J 0
(-1300 3150);
DISPLAY 1.234043 (-1300 3150);
PAINT GREEN (-1300 3150);
DISPLAY INVISIBLE (-1300 3150);
FORCEPROP 1 LAST PATH I42
J 0
(-1627 3275);
DISPLAY 0.872340 (-1627 3275);
PAINT GREEN (-1627 3275);
DISPLAY INVISIBLE (-1627 3275);
FORCEADD TAP..6
(-1625 3375);
FORCEPROP 3 LASTPIN (-1575 3375) SIG_NAME M_L_CLK_DP<3>
J 0
(-1565 3385);
DISPLAY 0.659574 (-1565 3385);
PAINT MONO (-1565 3385);
DISPLAY INVISIBLE (-1565 3385);
FORCEPROP 1 LASTPIN (-1575 3375) BN 3
J 0
(-1625 3385);
DISPLAY 0.617021 (-1625 3385);
PAINT PINK (-1625 3385);
FORCEPROP 2 LAST CDS_LIB mstr_standard
J 0
(-1625 3375);
DISPLAY 0.787234 (-1625 3375);
PAINT MONO (-1625 3375);
DISPLAY INVISIBLE (-1625 3375);
FORCEPROP 1 LAST BODY_TYPE PLUMBING
J 0
(-1625 3325);
DISPLAY 1.234043 (-1625 3325);
PAINT GREEN (-1625 3325);
DISPLAY INVISIBLE (-1625 3325);
FORCEPROP 1 LAST HDL_TAP TRUE
J 0
(-1300 3250);
DISPLAY 1.234043 (-1300 3250);
PAINT GREEN (-1300 3250);
DISPLAY INVISIBLE (-1300 3250);
FORCEPROP 1 LAST PATH I43
J 0
(-1627 3375);
DISPLAY 0.872340 (-1627 3375);
PAINT GREEN (-1627 3375);
DISPLAY INVISIBLE (-1627 3375);
FORCEADD TAP..6
(-1625 3475);
FORCEPROP 3 LASTPIN (-1575 3475) SIG_NAME M_L_BG<0>
J 0
(-1565 3485);
DISPLAY 0.659574 (-1565 3485);
PAINT MONO (-1565 3485);
DISPLAY INVISIBLE (-1565 3485);
FORCEPROP 1 LASTPIN (-1575 3475) BN 0
J 0
(-1625 3485);
DISPLAY 0.617021 (-1625 3485);
PAINT PINK (-1625 3485);
FORCEPROP 2 LAST CDS_LIB mstr_standard
J 0
(-1625 3475);
DISPLAY 0.787234 (-1625 3475);
PAINT MONO (-1625 3475);
DISPLAY INVISIBLE (-1625 3475);
FORCEPROP 1 LAST BODY_TYPE PLUMBING
J 0
(-1625 3425);
DISPLAY 1.234043 (-1625 3425);
PAINT GREEN (-1625 3425);
DISPLAY INVISIBLE (-1625 3425);
FORCEPROP 1 LAST HDL_TAP TRUE
J 0
(-1300 3350);
DISPLAY 1.234043 (-1300 3350);
PAINT GREEN (-1300 3350);
DISPLAY INVISIBLE (-1300 3350);
FORCEPROP 1 LAST PATH I44
J 0
(-1627 3475);
DISPLAY 0.872340 (-1627 3475);
PAINT GREEN (-1627 3475);
DISPLAY INVISIBLE (-1627 3475);
FORCEADD TAP..6
(-1625 3575);
FORCEPROP 3 LASTPIN (-1575 3575) SIG_NAME M_L_BA<0>
J 0
(-1565 3585);
DISPLAY 0.659574 (-1565 3585);
PAINT MONO (-1565 3585);
DISPLAY INVISIBLE (-1565 3585);
FORCEPROP 1 LASTPIN (-1575 3575) BN 0
J 0
(-1625 3585);
DISPLAY 0.617021 (-1625 3585);
PAINT PINK (-1625 3585);
FORCEPROP 2 LAST CDS_LIB mstr_standard
J 0
(-1625 3575);
DISPLAY 0.787234 (-1625 3575);
PAINT MONO (-1625 3575);
DISPLAY INVISIBLE (-1625 3575);
FORCEPROP 1 LAST BODY_TYPE PLUMBING
J 0
(-1625 3525);
DISPLAY 1.234043 (-1625 3525);
PAINT GREEN (-1625 3525);
DISPLAY INVISIBLE (-1625 3525);
FORCEPROP 1 LAST HDL_TAP TRUE
J 0
(-1300 3450);
DISPLAY 1.234043 (-1300 3450);
PAINT GREEN (-1300 3450);
DISPLAY INVISIBLE (-1300 3450);
FORCEPROP 1 LAST PATH I45
J 0
(-1627 3575);
DISPLAY 0.872340 (-1627 3575);
PAINT GREEN (-1627 3575);
DISPLAY INVISIBLE (-1627 3575);
FORCEADD TAP..6
(-1625 3525);
FORCEPROP 3 LASTPIN (-1575 3525) SIG_NAME M_L_BG<1>
J 0
(-1565 3535);
DISPLAY 0.659574 (-1565 3535);
PAINT MONO (-1565 3535);
DISPLAY INVISIBLE (-1565 3535);
FORCEPROP 1 LASTPIN (-1575 3525) BN 1
J 0
(-1625 3535);
DISPLAY 0.617021 (-1625 3535);
PAINT PINK (-1625 3535);
FORCEPROP 2 LAST CDS_LIB mstr_standard
J 0
(-1625 3525);
DISPLAY 0.787234 (-1625 3525);
PAINT MONO (-1625 3525);
DISPLAY INVISIBLE (-1625 3525);
FORCEPROP 1 LAST BODY_TYPE PLUMBING
J 0
(-1625 3475);
DISPLAY 1.234043 (-1625 3475);
PAINT GREEN (-1625 3475);
DISPLAY INVISIBLE (-1625 3475);
FORCEPROP 1 LAST HDL_TAP TRUE
J 0
(-1300 3400);
DISPLAY 1.234043 (-1300 3400);
PAINT GREEN (-1300 3400);
DISPLAY INVISIBLE (-1300 3400);
FORCEPROP 1 LAST PATH I46
J 0
(-1627 3525);
DISPLAY 0.872340 (-1627 3525);
PAINT GREEN (-1627 3525);
DISPLAY INVISIBLE (-1627 3525);
FORCEADD TAP..6
(-1625 3625);
FORCEPROP 3 LASTPIN (-1575 3625) SIG_NAME M_L_BA<1>
J 0
(-1565 3635);
DISPLAY 0.659574 (-1565 3635);
PAINT MONO (-1565 3635);
DISPLAY INVISIBLE (-1565 3635);
FORCEPROP 1 LASTPIN (-1575 3625) BN 1
J 0
(-1625 3635);
DISPLAY 0.617021 (-1625 3635);
PAINT PINK (-1625 3635);
FORCEPROP 2 LAST CDS_LIB mstr_standard
J 0
(-1625 3625);
DISPLAY 0.787234 (-1625 3625);
PAINT MONO (-1625 3625);
DISPLAY INVISIBLE (-1625 3625);
FORCEPROP 1 LAST BODY_TYPE PLUMBING
J 0
(-1625 3575);
DISPLAY 1.234043 (-1625 3575);
PAINT GREEN (-1625 3575);
DISPLAY INVISIBLE (-1625 3575);
FORCEPROP 1 LAST HDL_TAP TRUE
J 0
(-1300 3500);
DISPLAY 1.234043 (-1300 3500);
PAINT GREEN (-1300 3500);
DISPLAY INVISIBLE (-1300 3500);
FORCEPROP 1 LAST PATH I47
J 0
(-1627 3625);
DISPLAY 0.872340 (-1627 3625);
PAINT GREEN (-1627 3625);
DISPLAY INVISIBLE (-1627 3625);
FORCEADD TAP..6
(-1625 3725);
FORCEPROP 3 LASTPIN (-1575 3725) SIG_NAME M_L_MA<0>
J 0
(-1565 3735);
DISPLAY 0.659574 (-1565 3735);
PAINT MONO (-1565 3735);
DISPLAY INVISIBLE (-1565 3735);
FORCEPROP 1 LASTPIN (-1575 3725) BN 0
J 0
(-1625 3735);
DISPLAY 0.617021 (-1625 3735);
PAINT PINK (-1625 3735);
FORCEPROP 2 LAST CDS_LIB mstr_standard
J 2
(-1625 3725);
DISPLAY 0.787234 (-1625 3725);
PAINT MONO (-1625 3725);
DISPLAY INVISIBLE (-1625 3725);
FORCEPROP 1 LAST BODY_TYPE PLUMBING
J 0
(-1625 3675);
DISPLAY 1.234043 (-1625 3675);
PAINT GREEN (-1625 3675);
DISPLAY INVISIBLE (-1625 3675);
FORCEPROP 1 LAST HDL_TAP TRUE
J 0
(-1300 3600);
DISPLAY 1.234043 (-1300 3600);
PAINT GREEN (-1300 3600);
DISPLAY INVISIBLE (-1300 3600);
FORCEPROP 1 LAST PATH I48
J 0
(-1627 3725);
DISPLAY 0.872340 (-1627 3725);
PAINT GREEN (-1627 3725);
DISPLAY INVISIBLE (-1627 3725);
FORCEADD TAP..6
R 2
(-125 1425);
FORCEPROP 3 LASTPIN (-175 1425) SIG_NAME M_L_DQ<0>
J 0
(-165 1435);
DISPLAY 0.659574 (-165 1435);
PAINT MONO (-165 1435);
DISPLAY INVISIBLE (-165 1435);
FORCEPROP 1 LASTPIN (-175 1425) BN 0
J 2
(-125 1435);
DISPLAY 0.617021 (-125 1435);
PAINT PINK (-125 1435);
FORCEPROP 2 LAST CDS_LIB mstr_standard
J 2
(-125 1425);
DISPLAY 0.787234 (-125 1425);
PAINT MONO (-125 1425);
DISPLAY INVISIBLE (-125 1425);
FORCEPROP 1 LAST BODY_TYPE PLUMBING
J 2
(-125 1375);
DISPLAY 1.234043 (-125 1375);
PAINT GREEN (-125 1375);
DISPLAY INVISIBLE (-125 1375);
FORCEPROP 1 LAST HDL_TAP TRUE
J 2
(-450 1300);
DISPLAY 1.234043 (-450 1300);
PAINT GREEN (-450 1300);
DISPLAY INVISIBLE (-450 1300);
FORCEPROP 1 LAST PATH I49
J 2
(-123 1425);
DISPLAY 0.872340 (-123 1425);
PAINT GREEN (-123 1425);
DISPLAY INVISIBLE (-123 1425);
FORCEADD PVPP_KLM..1
(-3525 1925);
FORCEPROP 3 LASTPIN (-3525 1875) SIG_NAME PVPP_KLM\g
J 0
(-3515 1885);
DISPLAY 0.659574 (-3515 1885);
PAINT MONO (-3515 1885);
DISPLAY INVISIBLE (-3515 1885);
FORCEPROP 1 LAST VOLTAGE 2.5V
J 0
(-3570 1882);
DISPLAY 0.340426 (-3570 1882);
PAINT SKYBLUE (-3570 1882);
DISPLAY INVISIBLE (-3570 1882);
FORCEPROP 0 LAST BOM_COST MEM
J 0
(-3525 2025);
PAINT ORANGE (-3525 2025);
DISPLAY INVISIBLE (-3525 2025);
FORCEPROP 2 LAST CDS_LIB mstr_symbols
J 0
(-3525 1925);
PAINT ORANGE (-3525 1925);
DISPLAY INVISIBLE (-3525 1925);
FORCEPROP 1 LAST BODY_TYPE PLUMBING
J 0
(-3570 1882);
DISPLAY 0.340426 (-3570 1882);
PAINT GREEN (-3570 1882);
DISPLAY INVISIBLE (-3570 1882);
FORCEPROP 1 LAST PATH I5
J 0
(-3475 1950);
DISPLAY 0.872340 (-3475 1950);
PAINT AQUA (-3475 1950);
DISPLAY INVISIBLE (-3475 1950);
FORCEPROP 2 LAST ROOM DDR4_CH_D
J 0
(-3525 2025);
PAINT ORANGE (-3525 2025);
DISPLAY INVISIBLE (-3525 2025);
FORCEPROP 1 LAST HDL_POWER PVPP_KLM
J 1
(-3525 1975);
DISPLAY 0.872340 (-3525 1975);
PAINT GREEN (-3525 1975);
DISPLAY INVISIBLE (-3525 1975);
FORCEADD TAP..6
R 2
(-125 1625);
FORCEPROP 3 LASTPIN (-175 1625) SIG_NAME M_L_DQ<4>
J 0
(-165 1635);
DISPLAY 0.659574 (-165 1635);
PAINT MONO (-165 1635);
DISPLAY INVISIBLE (-165 1635);
FORCEPROP 1 LASTPIN (-175 1625) BN 4
J 2
(-125 1635);
DISPLAY 0.617021 (-125 1635);
PAINT PINK (-125 1635);
FORCEPROP 2 LAST CDS_LIB mstr_standard
J 2
(-125 1625);
DISPLAY 0.787234 (-125 1625);
PAINT MONO (-125 1625);
DISPLAY INVISIBLE (-125 1625);
FORCEPROP 1 LAST BODY_TYPE PLUMBING
J 2
(-125 1575);
DISPLAY 1.234043 (-125 1575);
PAINT GREEN (-125 1575);
DISPLAY INVISIBLE (-125 1575);
FORCEPROP 1 LAST HDL_TAP TRUE
J 2
(-450 1500);
DISPLAY 1.234043 (-450 1500);
PAINT GREEN (-450 1500);
DISPLAY INVISIBLE (-450 1500);
FORCEPROP 1 LAST PATH I50
J 2
(-123 1625);
DISPLAY 0.872340 (-123 1625);
PAINT GREEN (-123 1625);
DISPLAY INVISIBLE (-123 1625);
FORCEADD TAP..6
R 2
(-125 1475);
FORCEPROP 3 LASTPIN (-175 1475) SIG_NAME M_L_DQ<1>
J 0
(-165 1485);
DISPLAY 0.659574 (-165 1485);
PAINT MONO (-165 1485);
DISPLAY INVISIBLE (-165 1485);
FORCEPROP 1 LASTPIN (-175 1475) BN 1
J 2
(-125 1485);
DISPLAY 0.617021 (-125 1485);
PAINT PINK (-125 1485);
FORCEPROP 2 LAST CDS_LIB mstr_standard
J 2
(-125 1475);
DISPLAY 0.787234 (-125 1475);
PAINT MONO (-125 1475);
DISPLAY INVISIBLE (-125 1475);
FORCEPROP 1 LAST BODY_TYPE PLUMBING
J 2
(-125 1425);
DISPLAY 1.234043 (-125 1425);
PAINT GREEN (-125 1425);
DISPLAY INVISIBLE (-125 1425);
FORCEPROP 1 LAST HDL_TAP TRUE
J 2
(-450 1350);
DISPLAY 1.234043 (-450 1350);
PAINT GREEN (-450 1350);
DISPLAY INVISIBLE (-450 1350);
FORCEPROP 1 LAST PATH I51
J 2
(-123 1475);
DISPLAY 0.872340 (-123 1475);
PAINT GREEN (-123 1475);
DISPLAY INVISIBLE (-123 1475);
FORCEADD TAP..6
R 2
(-125 1525);
FORCEPROP 3 LASTPIN (-175 1525) SIG_NAME M_L_DQ<2>
J 0
(-165 1535);
DISPLAY 0.659574 (-165 1535);
PAINT MONO (-165 1535);
DISPLAY INVISIBLE (-165 1535);
FORCEPROP 1 LASTPIN (-175 1525) BN 2
J 2
(-125 1535);
DISPLAY 0.617021 (-125 1535);
PAINT PINK (-125 1535);
FORCEPROP 2 LAST CDS_LIB mstr_standard
J 2
(-125 1525);
DISPLAY 0.787234 (-125 1525);
PAINT MONO (-125 1525);
DISPLAY INVISIBLE (-125 1525);
FORCEPROP 1 LAST BODY_TYPE PLUMBING
J 2
(-125 1475);
DISPLAY 1.234043 (-125 1475);
PAINT GREEN (-125 1475);
DISPLAY INVISIBLE (-125 1475);
FORCEPROP 1 LAST HDL_TAP TRUE
J 2
(-450 1400);
DISPLAY 1.234043 (-450 1400);
PAINT GREEN (-450 1400);
DISPLAY INVISIBLE (-450 1400);
FORCEPROP 1 LAST PATH I52
J 2
(-123 1525);
DISPLAY 0.872340 (-123 1525);
PAINT GREEN (-123 1525);
DISPLAY INVISIBLE (-123 1525);
FORCEADD TAP..6
R 2
(-125 1675);
FORCEPROP 3 LASTPIN (-175 1675) SIG_NAME M_L_DQ<5>
J 0
(-165 1685);
DISPLAY 0.659574 (-165 1685);
PAINT MONO (-165 1685);
DISPLAY INVISIBLE (-165 1685);
FORCEPROP 1 LASTPIN (-175 1675) BN 5
J 2
(-125 1685);
DISPLAY 0.617021 (-125 1685);
PAINT PINK (-125 1685);
FORCEPROP 2 LAST CDS_LIB mstr_standard
J 2
(-125 1675);
DISPLAY 0.787234 (-125 1675);
PAINT MONO (-125 1675);
DISPLAY INVISIBLE (-125 1675);
FORCEPROP 1 LAST BODY_TYPE PLUMBING
J 2
(-125 1625);
DISPLAY 1.234043 (-125 1625);
PAINT GREEN (-125 1625);
DISPLAY INVISIBLE (-125 1625);
FORCEPROP 1 LAST HDL_TAP TRUE
J 2
(-450 1550);
DISPLAY 1.234043 (-450 1550);
PAINT GREEN (-450 1550);
DISPLAY INVISIBLE (-450 1550);
FORCEPROP 1 LAST PATH I53
J 2
(-123 1675);
DISPLAY 0.872340 (-123 1675);
PAINT GREEN (-123 1675);
DISPLAY INVISIBLE (-123 1675);
FORCEADD TAP..6
R 2
(-125 1575);
FORCEPROP 3 LASTPIN (-175 1575) SIG_NAME M_L_DQ<3>
J 0
(-165 1585);
DISPLAY 0.659574 (-165 1585);
PAINT MONO (-165 1585);
DISPLAY INVISIBLE (-165 1585);
FORCEPROP 1 LASTPIN (-175 1575) BN 3
J 2
(-125 1585);
DISPLAY 0.617021 (-125 1585);
PAINT PINK (-125 1585);
FORCEPROP 2 LAST CDS_LIB mstr_standard
J 2
(-125 1575);
DISPLAY 0.787234 (-125 1575);
PAINT MONO (-125 1575);
DISPLAY INVISIBLE (-125 1575);
FORCEPROP 1 LAST BODY_TYPE PLUMBING
J 2
(-125 1525);
DISPLAY 1.234043 (-125 1525);
PAINT GREEN (-125 1525);
DISPLAY INVISIBLE (-125 1525);
FORCEPROP 1 LAST HDL_TAP TRUE
J 2
(-450 1450);
DISPLAY 1.234043 (-450 1450);
PAINT GREEN (-450 1450);
DISPLAY INVISIBLE (-450 1450);
FORCEPROP 1 LAST PATH I54
J 2
(-123 1575);
DISPLAY 0.872340 (-123 1575);
PAINT GREEN (-123 1575);
DISPLAY INVISIBLE (-123 1575);
FORCEADD SCONN288_H44441003..4
(1375 1725);
FORCEPROP 1 LAST PART_NUMBER H44441-003
J 0
(925 675);
DISPLAY 0.617021 (925 675);
PAINT BLUE (925 675);
FORCEPROP 1 LAST MATERIAL SCONN
J 0
(925 2775);
DISPLAY 0.617021 (925 2775);
PAINT SKYBLUE (925 2775);
FORCEPROP 2 LASTPIN (875 2275) $PN 77
J 2
(865 2285);
DISPLAY 0.617021 (865 2285);
PAINT ORANGE (865 2285);
FORCEPROP 2 LASTPIN (875 2225) $PN 221
J 2
(865 2235);
DISPLAY 0.617021 (865 2235);
PAINT ORANGE (865 2235);
FORCEPROP 2 LASTPIN (875 2575) $PN 142
J 2
(865 2585);
DISPLAY 0.617021 (865 2585);
PAINT ORANGE (865 2585);
FORCEPROP 2 LASTPIN (875 2525) $PN 143
J 2
(865 2535);
DISPLAY 0.617021 (865 2535);
PAINT ORANGE (865 2535);
FORCEPROP 2 LASTPIN (875 2475) $PN 288
J 2
(865 2485);
DISPLAY 0.617021 (865 2485);
PAINT ORANGE (865 2485);
FORCEPROP 2 LASTPIN (875 2425) $PN 286
J 2
(865 2435);
DISPLAY 0.617021 (865 2435);
PAINT ORANGE (865 2435);
FORCEPROP 2 LASTPIN (875 2375) $PN 287
J 2
(865 2385);
DISPLAY 0.617021 (865 2385);
PAINT ORANGE (865 2385);
FORCEPROP 2 LASTPIN (875 2125) $PN 59
J 2
(865 2135);
DISPLAY 0.617021 (865 2135);
PAINT ORANGE (865 2135);
FORCEPROP 2 LASTPIN (875 2075) $PN 61
J 2
(865 2085);
DISPLAY 0.617021 (865 2085);
PAINT ORANGE (865 2085);
FORCEPROP 2 LASTPIN (875 2025) $PN 64
J 2
(865 2035);
DISPLAY 0.617021 (865 2035);
PAINT ORANGE (865 2035);
FORCEPROP 2 LASTPIN (875 1975) $PN 67
J 2
(865 1985);
DISPLAY 0.617021 (865 1985);
PAINT ORANGE (865 1985);
FORCEPROP 2 LASTPIN (875 1925) $PN 70
J 2
(865 1935);
DISPLAY 0.617021 (865 1935);
PAINT ORANGE (865 1935);
FORCEPROP 2 LASTPIN (875 1875) $PN 73
J 2
(865 1885);
DISPLAY 0.617021 (865 1885);
PAINT ORANGE (865 1885);
FORCEPROP 2 LASTPIN (875 1825) $PN 76
J 2
(865 1835);
DISPLAY 0.617021 (865 1835);
PAINT ORANGE (865 1835);
FORCEPROP 2 LASTPIN (875 1775) $PN 80
J 2
(865 1785);
DISPLAY 0.617021 (865 1785);
PAINT ORANGE (865 1785);
FORCEPROP 2 LASTPIN (875 1725) $PN 83
J 2
(865 1735);
DISPLAY 0.617021 (865 1735);
PAINT ORANGE (865 1735);
FORCEPROP 2 LASTPIN (875 1675) $PN 85
J 2
(865 1685);
DISPLAY 0.617021 (865 1685);
PAINT ORANGE (865 1685);
FORCEPROP 2 LASTPIN (875 1625) $PN 88
J 2
(865 1635);
DISPLAY 0.617021 (865 1635);
PAINT ORANGE (865 1635);
FORCEPROP 2 LASTPIN (875 1575) $PN 90
J 2
(865 1585);
DISPLAY 0.617021 (865 1585);
PAINT ORANGE (865 1585);
FORCEPROP 2 LASTPIN (875 1525) $PN 92
J 2
(865 1535);
DISPLAY 0.617021 (865 1535);
PAINT ORANGE (865 1535);
FORCEPROP 2 LASTPIN (875 1475) $PN 204
J 2
(865 1485);
DISPLAY 0.617021 (865 1485);
PAINT ORANGE (865 1485);
FORCEPROP 2 LASTPIN (875 1425) $PN 206
J 2
(865 1435);
DISPLAY 0.617021 (865 1435);
PAINT ORANGE (865 1435);
FORCEPROP 2 LASTPIN (875 1375) $PN 209
J 2
(865 1385);
DISPLAY 0.617021 (865 1385);
PAINT ORANGE (865 1385);
FORCEPROP 2 LASTPIN (875 1325) $PN 212
J 2
(865 1335);
DISPLAY 0.617021 (865 1335);
PAINT ORANGE (865 1335);
FORCEPROP 2 LASTPIN (875 1275) $PN 215
J 2
(865 1285);
DISPLAY 0.617021 (865 1285);
PAINT ORANGE (865 1285);
FORCEPROP 2 LASTPIN (875 1225) $PN 217
J 2
(865 1235);
DISPLAY 0.617021 (865 1235);
PAINT ORANGE (865 1235);
FORCEPROP 2 LASTPIN (875 1175) $PN 220
J 2
(865 1185);
DISPLAY 0.617021 (865 1185);
PAINT ORANGE (865 1185);
FORCEPROP 2 LASTPIN (875 1125) $PN 223
J 2
(865 1135);
DISPLAY 0.617021 (865 1135);
PAINT ORANGE (865 1135);
FORCEPROP 2 LASTPIN (875 1075) $PN 226
J 2
(865 1085);
DISPLAY 0.617021 (865 1085);
PAINT ORANGE (865 1085);
FORCEPROP 2 LASTPIN (875 1025) $PN 229
J 2
(865 1035);
DISPLAY 0.617021 (865 1035);
PAINT ORANGE (865 1035);
FORCEPROP 2 LASTPIN (875 975) $PN 231
J 2
(865 985);
DISPLAY 0.617021 (865 985);
PAINT ORANGE (865 985);
FORCEPROP 2 LASTPIN (875 925) $PN 233
J 2
(865 935);
DISPLAY 0.617021 (865 935);
PAINT ORANGE (865 935);
FORCEPROP 2 LASTPIN (875 875) $PN 236
J 2
(865 885);
DISPLAY 0.617021 (865 885);
PAINT ORANGE (865 885);
FORCEPROP 2 LASTPIN (1875 2575) $PN 1
J 0
(1885 2585);
DISPLAY 0.617021 (1885 2585);
PAINT ORANGE (1885 2585);
FORCEPROP 2 LASTPIN (1875 2525) $PN 145
J 0
(1885 2535);
DISPLAY 0.617021 (1885 2535);
PAINT ORANGE (1885 2535);
FORCEPROP 1 LAST LOCATION J9L2
J 0
(925 2825);
DISPLAY 0.617021 (925 2825);
PAINT AQUA (925 2825);
FORCEPROP 0 LAST BOM_SS NOPOP
J 0
(1231 2799);
DISPLAY 1.021277 (1231 2799);
PAINT BROWN (1231 2799);
DISPLAY BOTH (1231 2799);
FORCEPROP 1 LAST PACK_TYPE PIP
J 0
(925 2875);
PAINT SKYBLUE (925 2875);
DISPLAY INVISIBLE (925 2875);
FORCEPROP 2 LAST BOM_COST MEM
J 0
(1375 1725);
PAINT ORANGE (1375 1725);
DISPLAY INVISIBLE (1375 1725);
FORCEPROP 2 LAST CDS_LIB mstr_sconn
J 0
(1375 1725);
PAINT ORANGE (1375 1725);
DISPLAY INVISIBLE (1375 1725);
FORCEPROP 2 LAST SEC_TYPE PIP
J 0
(925 2875);
DISPLAY 1.021277 (925 2875);
PAINT ORANGE (925 2875);
DISPLAY INVISIBLE (925 2875);
FORCEPROP 2 LAST SEC 4
J 0
(925 2875);
DISPLAY 0.680851 (925 2875);
PAINT MONO (925 2875);
DISPLAY INVISIBLE (925 2875);
FORCEPROP 2 LAST CDS_LOCATION J9L2
J 0
(925 2825);
DISPLAY 0.617021 (925 2825);
PAINT AQUA (925 2825);
DISPLAY INVISIBLE (925 2825);
FORCEPROP 1 LAST PATH I55
J 0
(1375 2775);
PAINT GREEN (1375 2775);
DISPLAY INVISIBLE (1375 2775);
FORCEPROP 2 LAST ROOM DDR4_CH_L
J 0
(1375 1725);
PAINT ORANGE (1375 1725);
DISPLAY INVISIBLE (1375 1725);
FORCEADD TAP..6
R 2
(-125 1925);
FORCEPROP 3 LASTPIN (-175 1925) SIG_NAME M_L_DQ<10>
J 0
(-165 1935);
DISPLAY 0.659574 (-165 1935);
PAINT MONO (-165 1935);
DISPLAY INVISIBLE (-165 1935);
FORCEPROP 1 LASTPIN (-175 1925) BN 10
J 2
(-125 1935);
DISPLAY 0.617021 (-125 1935);
PAINT PINK (-125 1935);
FORCEPROP 2 LAST CDS_LIB mstr_standard
J 2
(-125 1925);
DISPLAY 0.787234 (-125 1925);
PAINT MONO (-125 1925);
DISPLAY INVISIBLE (-125 1925);
FORCEPROP 1 LAST BODY_TYPE PLUMBING
J 2
(-125 1875);
DISPLAY 1.234043 (-125 1875);
PAINT GREEN (-125 1875);
DISPLAY INVISIBLE (-125 1875);
FORCEPROP 1 LAST HDL_TAP TRUE
J 2
(-450 1800);
DISPLAY 1.234043 (-450 1800);
PAINT GREEN (-450 1800);
DISPLAY INVISIBLE (-450 1800);
FORCEPROP 1 LAST PATH I56
J 2
(-123 1925);
DISPLAY 0.872340 (-123 1925);
PAINT GREEN (-123 1925);
DISPLAY INVISIBLE (-123 1925);
FORCEADD TAP..6
R 2
(-125 1725);
FORCEPROP 3 LASTPIN (-175 1725) SIG_NAME M_L_DQ<6>
J 0
(-165 1735);
DISPLAY 0.659574 (-165 1735);
PAINT MONO (-165 1735);
DISPLAY INVISIBLE (-165 1735);
FORCEPROP 1 LASTPIN (-175 1725) BN 6
J 2
(-125 1735);
DISPLAY 0.617021 (-125 1735);
PAINT PINK (-125 1735);
FORCEPROP 2 LAST CDS_LIB mstr_standard
J 2
(-125 1725);
DISPLAY 0.787234 (-125 1725);
PAINT MONO (-125 1725);
DISPLAY INVISIBLE (-125 1725);
FORCEPROP 1 LAST BODY_TYPE PLUMBING
J 2
(-125 1675);
DISPLAY 1.234043 (-125 1675);
PAINT GREEN (-125 1675);
DISPLAY INVISIBLE (-125 1675);
FORCEPROP 1 LAST HDL_TAP TRUE
J 2
(-450 1600);
DISPLAY 1.234043 (-450 1600);
PAINT GREEN (-450 1600);
DISPLAY INVISIBLE (-450 1600);
FORCEPROP 1 LAST PATH I57
J 2
(-123 1725);
DISPLAY 0.872340 (-123 1725);
PAINT GREEN (-123 1725);
DISPLAY INVISIBLE (-123 1725);
FORCEADD TAP..6
R 2
(-125 1825);
FORCEPROP 3 LASTPIN (-175 1825) SIG_NAME M_L_DQ<8>
J 0
(-165 1835);
DISPLAY 0.659574 (-165 1835);
PAINT MONO (-165 1835);
DISPLAY INVISIBLE (-165 1835);
FORCEPROP 1 LASTPIN (-175 1825) BN 8
J 2
(-125 1835);
DISPLAY 0.617021 (-125 1835);
PAINT PINK (-125 1835);
FORCEPROP 2 LAST CDS_LIB mstr_standard
J 2
(-125 1825);
DISPLAY 0.787234 (-125 1825);
PAINT MONO (-125 1825);
DISPLAY INVISIBLE (-125 1825);
FORCEPROP 1 LAST BODY_TYPE PLUMBING
J 2
(-125 1775);
DISPLAY 1.234043 (-125 1775);
PAINT GREEN (-125 1775);
DISPLAY INVISIBLE (-125 1775);
FORCEPROP 1 LAST HDL_TAP TRUE
J 2
(-450 1700);
DISPLAY 1.234043 (-450 1700);
PAINT GREEN (-450 1700);
DISPLAY INVISIBLE (-450 1700);
FORCEPROP 1 LAST PATH I58
J 2
(-123 1825);
DISPLAY 0.872340 (-123 1825);
PAINT GREEN (-123 1825);
DISPLAY INVISIBLE (-123 1825);
FORCEADD TAP..6
R 2
(-125 1775);
FORCEPROP 3 LASTPIN (-175 1775) SIG_NAME M_L_DQ<7>
J 0
(-165 1785);
DISPLAY 0.659574 (-165 1785);
PAINT MONO (-165 1785);
DISPLAY INVISIBLE (-165 1785);
FORCEPROP 1 LASTPIN (-175 1775) BN 7
J 2
(-125 1785);
DISPLAY 0.617021 (-125 1785);
PAINT PINK (-125 1785);
FORCEPROP 2 LAST CDS_LIB mstr_standard
J 2
(-125 1775);
DISPLAY 0.787234 (-125 1775);
PAINT MONO (-125 1775);
DISPLAY INVISIBLE (-125 1775);
FORCEPROP 1 LAST BODY_TYPE PLUMBING
J 2
(-125 1725);
DISPLAY 1.234043 (-125 1725);
PAINT GREEN (-125 1725);
DISPLAY INVISIBLE (-125 1725);
FORCEPROP 1 LAST HDL_TAP TRUE
J 2
(-450 1650);
DISPLAY 1.234043 (-450 1650);
PAINT GREEN (-450 1650);
DISPLAY INVISIBLE (-450 1650);
FORCEPROP 1 LAST PATH I59
J 2
(-123 1775);
DISPLAY 0.872340 (-123 1775);
PAINT GREEN (-123 1775);
DISPLAY INVISIBLE (-123 1775);
FORCEADD OFFPAGE..5
(-2600 2225);
FORCEPROP 2 LAST $XR23 94 
J 0
(-3094 2261);
DISPLAY 0.638298 (-3094 2261);
PAINT MONO (-3094 2261);
FORCEPROP 2 LAST $XR22 88 
J 0
(-3004 2261);
DISPLAY 0.638298 (-3004 2261);
PAINT MONO (-3004 2261);
FORCEPROP 2 LAST $XR21 87 
J 0
(-2914 2261);
DISPLAY 0.638298 (-2914 2261);
PAINT MONO (-2914 2261);
FORCEPROP 2 LAST $XR20 85 
J 0
(-2824 2261);
DISPLAY 0.638298 (-2824 2261);
PAINT MONO (-2824 2261);
FORCEPROP 2 LAST $XR19 84 
J 0
(-3634 2189);
DISPLAY 0.638298 (-3634 2189);
PAINT MONO (-3634 2189);
FORCEPROP 2 LAST $XR18 83 
J 0
(-3544 2189);
DISPLAY 0.638298 (-3544 2189);
PAINT MONO (-3544 2189);
FORCEPROP 2 LAST $XR17 82 
J 0
(-3454 2189);
DISPLAY 0.638298 (-3454 2189);
PAINT MONO (-3454 2189);
FORCEPROP 2 LAST $XR16 81 
J 0
(-3364 2189);
DISPLAY 0.638298 (-3364 2189);
PAINT MONO (-3364 2189);
FORCEPROP 2 LAST $XR15 80 
J 0
(-3274 2189);
DISPLAY 0.638298 (-3274 2189);
PAINT MONO (-3274 2189);
FORCEPROP 2 LAST $XR14 79 
J 0
(-3184 2189);
DISPLAY 0.638298 (-3184 2189);
PAINT MONO (-3184 2189);
FORCEPROP 2 LAST $XR13 78 
J 0
(-3094 2189);
DISPLAY 0.638298 (-3094 2189);
PAINT MONO (-3094 2189);
FORCEPROP 2 LAST $XR12 77 
J 0
(-3004 2189);
DISPLAY 0.638298 (-3004 2189);
PAINT MONO (-3004 2189);
FORCEPROP 2 LAST $XR11 54 
J 0
(-2914 2189);
DISPLAY 0.638298 (-2914 2189);
PAINT MONO (-2914 2189);
FORCEPROP 2 LAST $XR10 53 
J 0
(-2824 2189);
DISPLAY 0.638298 (-2824 2189);
PAINT MONO (-2824 2189);
FORCEPROP 2 LAST $XR9 52 
J 0
(-3634 2225);
DISPLAY 0.638298 (-3634 2225);
PAINT MONO (-3634 2225);
FORCEPROP 2 LAST $XR8 51 
J 0
(-3544 2225);
DISPLAY 0.638298 (-3544 2225);
PAINT MONO (-3544 2225);
FORCEPROP 2 LAST $XR7 50 
J 0
(-3454 2225);
DISPLAY 0.638298 (-3454 2225);
PAINT MONO (-3454 2225);
FORCEPROP 2 LAST $XR6 49 
J 0
(-3364 2225);
DISPLAY 0.638298 (-3364 2225);
PAINT MONO (-3364 2225);
FORCEPROP 2 LAST $XR5 48 
J 0
(-3274 2225);
DISPLAY 0.638298 (-3274 2225);
PAINT MONO (-3274 2225);
FORCEPROP 2 LAST $XR4 47 
J 0
(-3184 2225);
DISPLAY 0.638298 (-3184 2225);
PAINT MONO (-3184 2225);
FORCEPROP 2 LAST $XR3 46 
J 0
(-3094 2225);
DISPLAY 0.638298 (-3094 2225);
PAINT MONO (-3094 2225);
FORCEPROP 2 LAST $XR2 45 
J 0
(-3004 2225);
DISPLAY 0.638298 (-3004 2225);
PAINT MONO (-3004 2225);
FORCEPROP 2 LAST $XR1 44 
J 0
(-2914 2225);
DISPLAY 0.638298 (-2914 2225);
PAINT MONO (-2914 2225);
FORCEPROP 2 LAST $XR0 43 
J 0
(-2824 2225);
DISPLAY 0.638298 (-2824 2225);
PAINT MONO (-2824 2225);
FORCEPROP 2 LAST CDS_LIB mstr_standard
J 0
(-2600 2225);
DISPLAY 0.787234 (-2600 2225);
PAINT MONO (-2600 2225);
DISPLAY INVISIBLE (-2600 2225);
FORCEPROP 1 LAST OFFPAGE TRUE
J 0
(-2275 2100);
DISPLAY 1.404255 (-2275 2100);
PAINT GREEN (-2275 2100);
DISPLAY INVISIBLE (-2275 2100);
FORCEPROP 1 LAST COMMENT_BODY TRUE
J 0
(-2500 2150);
DISPLAY 1.404255 (-2500 2150);
PAINT GREEN (-2500 2150);
DISPLAY INVISIBLE (-2500 2150);
FORCEPROP 2 LAST PATH I6
J 0
(-2800 2275);
DISPLAY 1.021277 (-2800 2275);
PAINT ORANGE (-2800 2275);
DISPLAY INVISIBLE (-2800 2275);
FORCEADD TAP..6
R 2
(-125 1975);
FORCEPROP 3 LASTPIN (-175 1975) SIG_NAME M_L_DQ<11>
J 0
(-165 1985);
DISPLAY 0.659574 (-165 1985);
PAINT MONO (-165 1985);
DISPLAY INVISIBLE (-165 1985);
FORCEPROP 1 LASTPIN (-175 1975) BN 11
J 2
(-125 1985);
DISPLAY 0.617021 (-125 1985);
PAINT PINK (-125 1985);
FORCEPROP 2 LAST CDS_LIB mstr_standard
J 2
(-125 1975);
DISPLAY 0.787234 (-125 1975);
PAINT MONO (-125 1975);
DISPLAY INVISIBLE (-125 1975);
FORCEPROP 1 LAST BODY_TYPE PLUMBING
J 2
(-125 1925);
DISPLAY 1.234043 (-125 1925);
PAINT GREEN (-125 1925);
DISPLAY INVISIBLE (-125 1925);
FORCEPROP 1 LAST HDL_TAP TRUE
J 2
(-450 1850);
DISPLAY 1.234043 (-450 1850);
PAINT GREEN (-450 1850);
DISPLAY INVISIBLE (-450 1850);
FORCEPROP 1 LAST PATH I60
J 2
(-123 1975);
DISPLAY 0.872340 (-123 1975);
PAINT GREEN (-123 1975);
DISPLAY INVISIBLE (-123 1975);
FORCEADD TAP..6
R 2
(-125 1875);
FORCEPROP 3 LASTPIN (-175 1875) SIG_NAME M_L_DQ<9>
J 0
(-165 1885);
DISPLAY 0.659574 (-165 1885);
PAINT MONO (-165 1885);
DISPLAY INVISIBLE (-165 1885);
FORCEPROP 1 LASTPIN (-175 1875) BN 9
J 2
(-125 1885);
DISPLAY 0.617021 (-125 1885);
PAINT PINK (-125 1885);
FORCEPROP 2 LAST CDS_LIB mstr_standard
J 2
(-125 1875);
DISPLAY 0.787234 (-125 1875);
PAINT MONO (-125 1875);
DISPLAY INVISIBLE (-125 1875);
FORCEPROP 1 LAST BODY_TYPE PLUMBING
J 2
(-125 1825);
DISPLAY 1.234043 (-125 1825);
PAINT GREEN (-125 1825);
DISPLAY INVISIBLE (-125 1825);
FORCEPROP 1 LAST HDL_TAP TRUE
J 2
(-450 1750);
DISPLAY 1.234043 (-450 1750);
PAINT GREEN (-450 1750);
DISPLAY INVISIBLE (-450 1750);
FORCEPROP 1 LAST PATH I61
J 2
(-123 1875);
DISPLAY 0.872340 (-123 1875);
PAINT GREEN (-123 1875);
DISPLAY INVISIBLE (-123 1875);
FORCEADD TAP..6
R 2
(-125 2025);
FORCEPROP 3 LASTPIN (-175 2025) SIG_NAME M_L_DQ<12>
J 0
(-165 2035);
DISPLAY 0.659574 (-165 2035);
PAINT MONO (-165 2035);
DISPLAY INVISIBLE (-165 2035);
FORCEPROP 1 LASTPIN (-175 2025) BN 12
J 2
(-125 2035);
DISPLAY 0.617021 (-125 2035);
PAINT PINK (-125 2035);
FORCEPROP 2 LAST CDS_LIB mstr_standard
J 2
(-125 2025);
DISPLAY 0.787234 (-125 2025);
PAINT MONO (-125 2025);
DISPLAY INVISIBLE (-125 2025);
FORCEPROP 1 LAST BODY_TYPE PLUMBING
J 2
(-125 1975);
DISPLAY 1.234043 (-125 1975);
PAINT GREEN (-125 1975);
DISPLAY INVISIBLE (-125 1975);
FORCEPROP 1 LAST HDL_TAP TRUE
J 2
(-450 1900);
DISPLAY 1.234043 (-450 1900);
PAINT GREEN (-450 1900);
DISPLAY INVISIBLE (-450 1900);
FORCEPROP 1 LAST PATH I62
J 2
(-123 2025);
DISPLAY 0.872340 (-123 2025);
PAINT GREEN (-123 2025);
DISPLAY INVISIBLE (-123 2025);
FORCEADD TAP..6
R 2
(-125 2075);
FORCEPROP 3 LASTPIN (-175 2075) SIG_NAME M_L_DQ<13>
J 0
(-165 2085);
DISPLAY 0.659574 (-165 2085);
PAINT MONO (-165 2085);
DISPLAY INVISIBLE (-165 2085);
FORCEPROP 1 LASTPIN (-175 2075) BN 13
J 2
(-125 2085);
DISPLAY 0.617021 (-125 2085);
PAINT PINK (-125 2085);
FORCEPROP 2 LAST CDS_LIB mstr_standard
J 2
(-125 2075);
DISPLAY 0.787234 (-125 2075);
PAINT MONO (-125 2075);
DISPLAY INVISIBLE (-125 2075);
FORCEPROP 1 LAST BODY_TYPE PLUMBING
J 2
(-125 2025);
DISPLAY 1.234043 (-125 2025);
PAINT GREEN (-125 2025);
DISPLAY INVISIBLE (-125 2025);
FORCEPROP 1 LAST HDL_TAP TRUE
J 2
(-450 1950);
DISPLAY 1.234043 (-450 1950);
PAINT GREEN (-450 1950);
DISPLAY INVISIBLE (-450 1950);
FORCEPROP 1 LAST PATH I63
J 2
(-123 2075);
DISPLAY 0.872340 (-123 2075);
PAINT GREEN (-123 2075);
DISPLAY INVISIBLE (-123 2075);
FORCEADD TAP..6
R 2
(-125 2225);
FORCEPROP 3 LASTPIN (-175 2225) SIG_NAME M_L_DQ<16>
J 0
(-165 2235);
DISPLAY 0.659574 (-165 2235);
PAINT MONO (-165 2235);
DISPLAY INVISIBLE (-165 2235);
FORCEPROP 1 LASTPIN (-175 2225) BN 16
J 2
(-125 2235);
DISPLAY 0.617021 (-125 2235);
PAINT PINK (-125 2235);
FORCEPROP 2 LAST CDS_LIB mstr_standard
J 2
(-125 2225);
DISPLAY 0.787234 (-125 2225);
PAINT MONO (-125 2225);
DISPLAY INVISIBLE (-125 2225);
FORCEPROP 1 LAST BODY_TYPE PLUMBING
J 2
(-125 2175);
DISPLAY 1.234043 (-125 2175);
PAINT GREEN (-125 2175);
DISPLAY INVISIBLE (-125 2175);
FORCEPROP 1 LAST HDL_TAP TRUE
J 2
(-450 2100);
DISPLAY 1.234043 (-450 2100);
PAINT GREEN (-450 2100);
DISPLAY INVISIBLE (-450 2100);
FORCEPROP 1 LAST PATH I64
J 2
(-123 2225);
DISPLAY 0.872340 (-123 2225);
PAINT GREEN (-123 2225);
DISPLAY INVISIBLE (-123 2225);
FORCEADD TAP..6
R 2
(-125 2175);
FORCEPROP 3 LASTPIN (-175 2175) SIG_NAME M_L_DQ<15>
J 0
(-165 2185);
DISPLAY 0.659574 (-165 2185);
PAINT MONO (-165 2185);
DISPLAY INVISIBLE (-165 2185);
FORCEPROP 1 LASTPIN (-175 2175) BN 15
J 2
(-125 2185);
DISPLAY 0.617021 (-125 2185);
PAINT PINK (-125 2185);
FORCEPROP 2 LAST CDS_LIB mstr_standard
J 2
(-125 2175);
DISPLAY 0.787234 (-125 2175);
PAINT MONO (-125 2175);
DISPLAY INVISIBLE (-125 2175);
FORCEPROP 1 LAST BODY_TYPE PLUMBING
J 2
(-125 2125);
DISPLAY 1.234043 (-125 2125);
PAINT GREEN (-125 2125);
DISPLAY INVISIBLE (-125 2125);
FORCEPROP 1 LAST HDL_TAP TRUE
J 2
(-450 2050);
DISPLAY 1.234043 (-450 2050);
PAINT GREEN (-450 2050);
DISPLAY INVISIBLE (-450 2050);
FORCEPROP 1 LAST PATH I65
J 2
(-123 2175);
DISPLAY 0.872340 (-123 2175);
PAINT GREEN (-123 2175);
DISPLAY INVISIBLE (-123 2175);
FORCEADD TAP..6
R 2
(-125 2125);
FORCEPROP 3 LASTPIN (-175 2125) SIG_NAME M_L_DQ<14>
J 0
(-165 2135);
DISPLAY 0.659574 (-165 2135);
PAINT MONO (-165 2135);
DISPLAY INVISIBLE (-165 2135);
FORCEPROP 1 LASTPIN (-175 2125) BN 14
J 2
(-125 2135);
DISPLAY 0.617021 (-125 2135);
PAINT PINK (-125 2135);
FORCEPROP 2 LAST CDS_LIB mstr_standard
J 2
(-125 2125);
DISPLAY 0.787234 (-125 2125);
PAINT MONO (-125 2125);
DISPLAY INVISIBLE (-125 2125);
FORCEPROP 1 LAST BODY_TYPE PLUMBING
J 2
(-125 2075);
DISPLAY 1.234043 (-125 2075);
PAINT GREEN (-125 2075);
DISPLAY INVISIBLE (-125 2075);
FORCEPROP 1 LAST HDL_TAP TRUE
J 2
(-450 2000);
DISPLAY 1.234043 (-450 2000);
PAINT GREEN (-450 2000);
DISPLAY INVISIBLE (-450 2000);
FORCEPROP 1 LAST PATH I66
J 2
(-123 2125);
DISPLAY 0.872340 (-123 2125);
PAINT GREEN (-123 2125);
DISPLAY INVISIBLE (-123 2125);
FORCEADD TAP..6
R 2
(-125 2325);
FORCEPROP 3 LASTPIN (-175 2325) SIG_NAME M_L_DQ<18>
J 0
(-165 2335);
DISPLAY 0.659574 (-165 2335);
PAINT MONO (-165 2335);
DISPLAY INVISIBLE (-165 2335);
FORCEPROP 1 LASTPIN (-175 2325) BN 18
J 2
(-125 2335);
DISPLAY 0.617021 (-125 2335);
PAINT PINK (-125 2335);
FORCEPROP 2 LAST CDS_LIB mstr_standard
J 2
(-125 2325);
DISPLAY 0.787234 (-125 2325);
PAINT MONO (-125 2325);
DISPLAY INVISIBLE (-125 2325);
FORCEPROP 1 LAST BODY_TYPE PLUMBING
J 2
(-125 2275);
DISPLAY 1.234043 (-125 2275);
PAINT GREEN (-125 2275);
DISPLAY INVISIBLE (-125 2275);
FORCEPROP 1 LAST HDL_TAP TRUE
J 2
(-450 2200);
DISPLAY 1.234043 (-450 2200);
PAINT GREEN (-450 2200);
DISPLAY INVISIBLE (-450 2200);
FORCEPROP 1 LAST PATH I67
J 2
(-123 2325);
DISPLAY 0.872340 (-123 2325);
PAINT GREEN (-123 2325);
DISPLAY INVISIBLE (-123 2325);
FORCEADD TAP..6
R 2
(-125 2275);
FORCEPROP 3 LASTPIN (-175 2275) SIG_NAME M_L_DQ<17>
J 0
(-165 2285);
DISPLAY 0.659574 (-165 2285);
PAINT MONO (-165 2285);
DISPLAY INVISIBLE (-165 2285);
FORCEPROP 1 LASTPIN (-175 2275) BN 17
J 2
(-125 2285);
DISPLAY 0.617021 (-125 2285);
PAINT PINK (-125 2285);
FORCEPROP 2 LAST CDS_LIB mstr_standard
J 2
(-125 2275);
DISPLAY 0.787234 (-125 2275);
PAINT MONO (-125 2275);
DISPLAY INVISIBLE (-125 2275);
FORCEPROP 1 LAST BODY_TYPE PLUMBING
J 2
(-125 2225);
DISPLAY 1.234043 (-125 2225);
PAINT GREEN (-125 2225);
DISPLAY INVISIBLE (-125 2225);
FORCEPROP 1 LAST HDL_TAP TRUE
J 2
(-450 2150);
DISPLAY 1.234043 (-450 2150);
PAINT GREEN (-450 2150);
DISPLAY INVISIBLE (-450 2150);
FORCEPROP 1 LAST PATH I68
J 2
(-123 2275);
DISPLAY 0.872340 (-123 2275);
PAINT GREEN (-123 2275);
DISPLAY INVISIBLE (-123 2275);
FORCEADD TAP..6
R 2
(-125 2475);
FORCEPROP 3 LASTPIN (-175 2475) SIG_NAME M_L_DQ<21>
J 0
(-165 2485);
DISPLAY 0.659574 (-165 2485);
PAINT MONO (-165 2485);
DISPLAY INVISIBLE (-165 2485);
FORCEPROP 1 LASTPIN (-175 2475) BN 21
J 2
(-125 2485);
DISPLAY 0.617021 (-125 2485);
PAINT PINK (-125 2485);
FORCEPROP 2 LAST CDS_LIB mstr_standard
J 2
(-125 2475);
DISPLAY 0.787234 (-125 2475);
PAINT MONO (-125 2475);
DISPLAY INVISIBLE (-125 2475);
FORCEPROP 1 LAST BODY_TYPE PLUMBING
J 2
(-125 2425);
DISPLAY 1.234043 (-125 2425);
PAINT GREEN (-125 2425);
DISPLAY INVISIBLE (-125 2425);
FORCEPROP 1 LAST HDL_TAP TRUE
J 2
(-450 2350);
DISPLAY 1.234043 (-450 2350);
PAINT GREEN (-450 2350);
DISPLAY INVISIBLE (-450 2350);
FORCEPROP 1 LAST PATH I69
J 2
(-123 2475);
DISPLAY 0.872340 (-123 2475);
PAINT GREEN (-123 2475);
DISPLAY INVISIBLE (-123 2475);
FORCEADD OFFPAGE..1
(-2425 1875);
FORCEPROP 2 LAST $XR1 85 
J 0
(-2766 1875);
DISPLAY 0.638298 (-2766 1875);
PAINT MONO (-2766 1875);
FORCEPROP 2 LAST $XR0 61 
J 0
(-2676 1875);
DISPLAY 0.638298 (-2676 1875);
PAINT MONO (-2676 1875);
FORCEPROP 2 LAST CDS_LIB mstr_standard
J 0
(-2425 1875);
DISPLAY 0.787234 (-2425 1875);
PAINT MONO (-2425 1875);
DISPLAY INVISIBLE (-2425 1875);
FORCEPROP 1 LAST OFFPAGE TRUE
J 0
(-2100 1750);
DISPLAY 0.936170 (-2100 1750);
PAINT GREEN (-2100 1750);
DISPLAY INVISIBLE (-2100 1750);
FORCEPROP 1 LAST COMMENT_BODY TRUE
J 0
(-2300 1775);
DISPLAY 0.936170 (-2300 1775);
PAINT GREEN (-2300 1775);
DISPLAY INVISIBLE (-2300 1775);
FORCEPROP 2 LAST PATH I7
J 0
(-2675 1925);
DISPLAY 1.021277 (-2675 1925);
PAINT ORANGE (-2675 1925);
DISPLAY INVISIBLE (-2675 1925);
FORCEADD TAP..6
R 2
(-125 2425);
FORCEPROP 3 LASTPIN (-175 2425) SIG_NAME M_L_DQ<20>
J 0
(-165 2435);
DISPLAY 0.659574 (-165 2435);
PAINT MONO (-165 2435);
DISPLAY INVISIBLE (-165 2435);
FORCEPROP 1 LASTPIN (-175 2425) BN 20
J 2
(-125 2435);
DISPLAY 0.617021 (-125 2435);
PAINT PINK (-125 2435);
FORCEPROP 2 LAST CDS_LIB mstr_standard
J 2
(-125 2425);
DISPLAY 0.787234 (-125 2425);
PAINT MONO (-125 2425);
DISPLAY INVISIBLE (-125 2425);
FORCEPROP 1 LAST BODY_TYPE PLUMBING
J 2
(-125 2375);
DISPLAY 1.234043 (-125 2375);
PAINT GREEN (-125 2375);
DISPLAY INVISIBLE (-125 2375);
FORCEPROP 1 LAST HDL_TAP TRUE
J 2
(-450 2300);
DISPLAY 1.234043 (-450 2300);
PAINT GREEN (-450 2300);
DISPLAY INVISIBLE (-450 2300);
FORCEPROP 1 LAST PATH I70
J 2
(-123 2425);
DISPLAY 0.872340 (-123 2425);
PAINT GREEN (-123 2425);
DISPLAY INVISIBLE (-123 2425);
FORCEADD TAP..6
R 2
(-125 2375);
FORCEPROP 3 LASTPIN (-175 2375) SIG_NAME M_L_DQ<19>
J 0
(-165 2385);
DISPLAY 0.659574 (-165 2385);
PAINT MONO (-165 2385);
DISPLAY INVISIBLE (-165 2385);
FORCEPROP 1 LASTPIN (-175 2375) BN 19
J 2
(-125 2385);
DISPLAY 0.617021 (-125 2385);
PAINT PINK (-125 2385);
FORCEPROP 2 LAST CDS_LIB mstr_standard
J 2
(-125 2375);
DISPLAY 0.787234 (-125 2375);
PAINT MONO (-125 2375);
DISPLAY INVISIBLE (-125 2375);
FORCEPROP 1 LAST BODY_TYPE PLUMBING
J 2
(-125 2325);
DISPLAY 1.234043 (-125 2325);
PAINT GREEN (-125 2325);
DISPLAY INVISIBLE (-125 2325);
FORCEPROP 1 LAST HDL_TAP TRUE
J 2
(-450 2250);
DISPLAY 1.234043 (-450 2250);
PAINT GREEN (-450 2250);
DISPLAY INVISIBLE (-450 2250);
FORCEPROP 1 LAST PATH I71
J 2
(-123 2375);
DISPLAY 0.872340 (-123 2375);
PAINT GREEN (-123 2375);
DISPLAY INVISIBLE (-123 2375);
FORCEADD TAP..6
R 2
(-125 2675);
FORCEPROP 3 LASTPIN (-175 2675) SIG_NAME M_L_DQ<25>
J 0
(-165 2685);
DISPLAY 0.659574 (-165 2685);
PAINT MONO (-165 2685);
DISPLAY INVISIBLE (-165 2685);
FORCEPROP 1 LASTPIN (-175 2675) BN 25
J 2
(-125 2685);
DISPLAY 0.617021 (-125 2685);
PAINT PINK (-125 2685);
FORCEPROP 2 LAST CDS_LIB mstr_standard
J 2
(-125 2675);
DISPLAY 0.787234 (-125 2675);
PAINT MONO (-125 2675);
DISPLAY INVISIBLE (-125 2675);
FORCEPROP 1 LAST BODY_TYPE PLUMBING
J 2
(-125 2625);
DISPLAY 1.234043 (-125 2625);
PAINT GREEN (-125 2625);
DISPLAY INVISIBLE (-125 2625);
FORCEPROP 1 LAST HDL_TAP TRUE
J 2
(-450 2550);
DISPLAY 1.234043 (-450 2550);
PAINT GREEN (-450 2550);
DISPLAY INVISIBLE (-450 2550);
FORCEPROP 1 LAST PATH I72
J 2
(-123 2675);
DISPLAY 0.872340 (-123 2675);
PAINT GREEN (-123 2675);
DISPLAY INVISIBLE (-123 2675);
FORCEADD TAP..6
R 2
(-125 2625);
FORCEPROP 3 LASTPIN (-175 2625) SIG_NAME M_L_DQ<24>
J 0
(-165 2635);
DISPLAY 0.659574 (-165 2635);
PAINT MONO (-165 2635);
DISPLAY INVISIBLE (-165 2635);
FORCEPROP 1 LASTPIN (-175 2625) BN 24
J 2
(-125 2635);
DISPLAY 0.617021 (-125 2635);
PAINT PINK (-125 2635);
FORCEPROP 2 LAST CDS_LIB mstr_standard
J 2
(-125 2625);
DISPLAY 0.787234 (-125 2625);
PAINT MONO (-125 2625);
DISPLAY INVISIBLE (-125 2625);
FORCEPROP 1 LAST BODY_TYPE PLUMBING
J 2
(-125 2575);
DISPLAY 1.234043 (-125 2575);
PAINT GREEN (-125 2575);
DISPLAY INVISIBLE (-125 2575);
FORCEPROP 1 LAST HDL_TAP TRUE
J 2
(-450 2500);
DISPLAY 1.234043 (-450 2500);
PAINT GREEN (-450 2500);
DISPLAY INVISIBLE (-450 2500);
FORCEPROP 1 LAST PATH I73
J 2
(-123 2625);
DISPLAY 0.872340 (-123 2625);
PAINT GREEN (-123 2625);
DISPLAY INVISIBLE (-123 2625);
FORCEADD TAP..6
R 2
(-125 2725);
FORCEPROP 3 LASTPIN (-175 2725) SIG_NAME M_L_DQ<26>
J 0
(-165 2735);
DISPLAY 0.659574 (-165 2735);
PAINT MONO (-165 2735);
DISPLAY INVISIBLE (-165 2735);
FORCEPROP 1 LASTPIN (-175 2725) BN 26
J 2
(-125 2735);
DISPLAY 0.617021 (-125 2735);
PAINT PINK (-125 2735);
FORCEPROP 2 LAST CDS_LIB mstr_standard
J 2
(-125 2725);
DISPLAY 0.787234 (-125 2725);
PAINT MONO (-125 2725);
DISPLAY INVISIBLE (-125 2725);
FORCEPROP 1 LAST BODY_TYPE PLUMBING
J 2
(-125 2675);
DISPLAY 1.234043 (-125 2675);
PAINT GREEN (-125 2675);
DISPLAY INVISIBLE (-125 2675);
FORCEPROP 1 LAST HDL_TAP TRUE
J 2
(-450 2600);
DISPLAY 1.234043 (-450 2600);
PAINT GREEN (-450 2600);
DISPLAY INVISIBLE (-450 2600);
FORCEPROP 1 LAST PATH I74
J 2
(-123 2725);
DISPLAY 0.872340 (-123 2725);
PAINT GREEN (-123 2725);
DISPLAY INVISIBLE (-123 2725);
FORCEADD TAP..6
R 2
(-125 2525);
FORCEPROP 3 LASTPIN (-175 2525) SIG_NAME M_L_DQ<22>
J 0
(-165 2535);
DISPLAY 0.659574 (-165 2535);
PAINT MONO (-165 2535);
DISPLAY INVISIBLE (-165 2535);
FORCEPROP 1 LASTPIN (-175 2525) BN 22
J 2
(-125 2535);
DISPLAY 0.617021 (-125 2535);
PAINT PINK (-125 2535);
FORCEPROP 2 LAST CDS_LIB mstr_standard
J 2
(-125 2525);
DISPLAY 0.787234 (-125 2525);
PAINT MONO (-125 2525);
DISPLAY INVISIBLE (-125 2525);
FORCEPROP 1 LAST BODY_TYPE PLUMBING
J 2
(-125 2475);
DISPLAY 1.234043 (-125 2475);
PAINT GREEN (-125 2475);
DISPLAY INVISIBLE (-125 2475);
FORCEPROP 1 LAST HDL_TAP TRUE
J 2
(-450 2400);
DISPLAY 1.234043 (-450 2400);
PAINT GREEN (-450 2400);
DISPLAY INVISIBLE (-450 2400);
FORCEPROP 1 LAST PATH I75
J 2
(-123 2525);
DISPLAY 0.872340 (-123 2525);
PAINT GREEN (-123 2525);
DISPLAY INVISIBLE (-123 2525);
FORCEADD TAP..6
R 2
(-125 2575);
FORCEPROP 3 LASTPIN (-175 2575) SIG_NAME M_L_DQ<23>
J 0
(-165 2585);
DISPLAY 0.659574 (-165 2585);
PAINT MONO (-165 2585);
DISPLAY INVISIBLE (-165 2585);
FORCEPROP 1 LASTPIN (-175 2575) BN 23
J 2
(-125 2585);
DISPLAY 0.617021 (-125 2585);
PAINT PINK (-125 2585);
FORCEPROP 2 LAST CDS_LIB mstr_standard
J 2
(-125 2575);
DISPLAY 0.787234 (-125 2575);
PAINT MONO (-125 2575);
DISPLAY INVISIBLE (-125 2575);
FORCEPROP 1 LAST BODY_TYPE PLUMBING
J 2
(-125 2525);
DISPLAY 1.234043 (-125 2525);
PAINT GREEN (-125 2525);
DISPLAY INVISIBLE (-125 2525);
FORCEPROP 1 LAST HDL_TAP TRUE
J 2
(-450 2450);
DISPLAY 1.234043 (-450 2450);
PAINT GREEN (-450 2450);
DISPLAY INVISIBLE (-450 2450);
FORCEPROP 1 LAST PATH I76
J 2
(-123 2575);
DISPLAY 0.872340 (-123 2575);
PAINT GREEN (-123 2575);
DISPLAY INVISIBLE (-123 2575);
FORCEADD PVDDQ_KLM..1
(275 2275);
FORCEPROP 3 LASTPIN (275 2225) SIG_NAME PVDDQ_KLM\g
J 0
(285 2235);
DISPLAY 0.659574 (285 2235);
PAINT MONO (285 2235);
DISPLAY INVISIBLE (285 2235);
FORCEPROP 1 LAST VOLTAGE 1.2V
J 0
(230 2232);
DISPLAY 0.340426 (230 2232);
PAINT SKYBLUE (230 2232);
DISPLAY INVISIBLE (230 2232);
FORCEPROP 2 LAST BOM_COST MEM
J 0
(275 2280);
PAINT ORANGE (275 2280);
DISPLAY INVISIBLE (275 2280);
FORCEPROP 2 LAST CDS_LIB mstr_symbols
J 0
(275 2275);
PAINT ORANGE (275 2275);
DISPLAY INVISIBLE (275 2275);
FORCEPROP 1 LAST BODY_TYPE PLUMBING
J 0
(230 2232);
DISPLAY 0.340426 (230 2232);
PAINT GREEN (230 2232);
DISPLAY INVISIBLE (230 2232);
FORCEPROP 1 LAST PATH I77
J 0
(325 2300);
DISPLAY 0.872340 (325 2300);
PAINT AQUA (325 2300);
DISPLAY INVISIBLE (325 2300);
FORCEPROP 2 LAST ROOM DDR4_CH_D
J 0
(275 2375);
DISPLAY 0.787234 (275 2375);
PAINT ORANGE (275 2375);
DISPLAY INVISIBLE (275 2375);
FORCEPROP 1 LAST HDL_POWER PVDDQ_KLM
J 1
(275 2325);
DISPLAY 0.872340 (275 2325);
PAINT GREEN (275 2325);
DISPLAY INVISIBLE (275 2325);
FORCEADD PVTT_KLM..1
(525 2425);
FORCEPROP 3 LASTPIN (525 2375) SIG_NAME PVTT_KLM\g
J 0
(535 2385);
DISPLAY 0.659574 (535 2385);
PAINT MONO (535 2385);
DISPLAY INVISIBLE (535 2385);
FORCEPROP 1 LAST VOLTAGE 0.6V
J 0
(480 2382);
DISPLAY 0.340426 (480 2382);
PAINT SKYBLUE (480 2382);
DISPLAY INVISIBLE (480 2382);
FORCEPROP 2 LAST BOM_COST MEM
J 0
(525 2430);
PAINT ORANGE (525 2430);
DISPLAY INVISIBLE (525 2430);
FORCEPROP 2 LAST CDS_LIB mstr_symbols
J 0
(525 2425);
PAINT ORANGE (525 2425);
DISPLAY INVISIBLE (525 2425);
FORCEPROP 1 LAST BODY_TYPE PLUMBING
J 0
(480 2382);
DISPLAY 0.340426 (480 2382);
PAINT GREEN (480 2382);
DISPLAY INVISIBLE (480 2382);
FORCEPROP 1 LAST PATH I78
J 0
(575 2450);
DISPLAY 0.872340 (575 2450);
PAINT AQUA (575 2450);
DISPLAY INVISIBLE (575 2450);
FORCEPROP 2 LAST ROOM DDR4_CH_D
J 0
(525 2525);
DISPLAY 0.787234 (525 2525);
PAINT ORANGE (525 2525);
DISPLAY INVISIBLE (525 2525);
FORCEPROP 1 LAST HDL_POWER PVTT_KLM
J 1
(525 2475);
DISPLAY 0.872340 (525 2475);
PAINT GREEN (525 2475);
DISPLAY INVISIBLE (525 2475);
FORCEADD TAP..6
R 2
(-125 2775);
FORCEPROP 3 LASTPIN (-175 2775) SIG_NAME M_L_DQ<27>
J 0
(-165 2785);
DISPLAY 0.659574 (-165 2785);
PAINT MONO (-165 2785);
DISPLAY INVISIBLE (-165 2785);
FORCEPROP 1 LASTPIN (-175 2775) BN 27
J 2
(-125 2785);
DISPLAY 0.617021 (-125 2785);
PAINT PINK (-125 2785);
FORCEPROP 2 LAST CDS_LIB mstr_standard
J 2
(-125 2775);
DISPLAY 0.787234 (-125 2775);
PAINT MONO (-125 2775);
DISPLAY INVISIBLE (-125 2775);
FORCEPROP 1 LAST BODY_TYPE PLUMBING
J 2
(-125 2725);
DISPLAY 1.234043 (-125 2725);
PAINT GREEN (-125 2725);
DISPLAY INVISIBLE (-125 2725);
FORCEPROP 1 LAST HDL_TAP TRUE
J 2
(-450 2650);
DISPLAY 1.234043 (-450 2650);
PAINT GREEN (-450 2650);
DISPLAY INVISIBLE (-450 2650);
FORCEPROP 1 LAST PATH I79
J 2
(-123 2775);
DISPLAY 0.872340 (-123 2775);
PAINT GREEN (-123 2775);
DISPLAY INVISIBLE (-123 2775);
FORCEADD OFFPAGE..5
(-2450 1925);
FORCEPROP 2 LAST $XR1 61 
J 0
(-2764 1925);
DISPLAY 0.638298 (-2764 1925);
PAINT MONO (-2764 1925);
FORCEPROP 2 LAST $XR0 85 
J 0
(-2674 1925);
DISPLAY 0.638298 (-2674 1925);
PAINT MONO (-2674 1925);
FORCEPROP 2 LAST CDS_LIB mstr_standard
J 0
(-2450 1925);
DISPLAY 0.787234 (-2450 1925);
PAINT MONO (-2450 1925);
DISPLAY INVISIBLE (-2450 1925);
FORCEPROP 1 LAST OFFPAGE TRUE
J 0
(-2125 1800);
DISPLAY 1.404255 (-2125 1800);
PAINT GREEN (-2125 1800);
DISPLAY INVISIBLE (-2125 1800);
FORCEPROP 1 LAST COMMENT_BODY TRUE
J 0
(-2350 1850);
DISPLAY 1.404255 (-2350 1850);
PAINT GREEN (-2350 1850);
DISPLAY INVISIBLE (-2350 1850);
FORCEPROP 2 LAST PATH I8
J 0
(-2650 1975);
DISPLAY 1.021277 (-2650 1975);
PAINT ORANGE (-2650 1975);
DISPLAY INVISIBLE (-2650 1975);
FORCEADD TAP..6
R 2
(-125 2825);
FORCEPROP 3 LASTPIN (-175 2825) SIG_NAME M_L_DQ<28>
J 0
(-165 2835);
DISPLAY 0.659574 (-165 2835);
PAINT MONO (-165 2835);
DISPLAY INVISIBLE (-165 2835);
FORCEPROP 1 LASTPIN (-175 2825) BN 28
J 2
(-125 2835);
DISPLAY 0.617021 (-125 2835);
PAINT PINK (-125 2835);
FORCEPROP 2 LAST CDS_LIB mstr_standard
J 2
(-125 2825);
DISPLAY 0.787234 (-125 2825);
PAINT MONO (-125 2825);
DISPLAY INVISIBLE (-125 2825);
FORCEPROP 1 LAST BODY_TYPE PLUMBING
J 2
(-125 2775);
DISPLAY 1.234043 (-125 2775);
PAINT GREEN (-125 2775);
DISPLAY INVISIBLE (-125 2775);
FORCEPROP 1 LAST HDL_TAP TRUE
J 2
(-450 2700);
DISPLAY 1.234043 (-450 2700);
PAINT GREEN (-450 2700);
DISPLAY INVISIBLE (-450 2700);
FORCEPROP 1 LAST PATH I80
J 2
(-123 2825);
DISPLAY 0.872340 (-123 2825);
PAINT GREEN (-123 2825);
DISPLAY INVISIBLE (-123 2825);
FORCEADD TAP..6
R 2
(-125 2875);
FORCEPROP 3 LASTPIN (-175 2875) SIG_NAME M_L_DQ<29>
J 0
(-165 2885);
DISPLAY 0.659574 (-165 2885);
PAINT MONO (-165 2885);
DISPLAY INVISIBLE (-165 2885);
FORCEPROP 1 LASTPIN (-175 2875) BN 29
J 2
(-125 2885);
DISPLAY 0.617021 (-125 2885);
PAINT PINK (-125 2885);
FORCEPROP 2 LAST CDS_LIB mstr_standard
J 2
(-125 2875);
DISPLAY 0.787234 (-125 2875);
PAINT MONO (-125 2875);
DISPLAY INVISIBLE (-125 2875);
FORCEPROP 1 LAST BODY_TYPE PLUMBING
J 2
(-125 2825);
DISPLAY 1.234043 (-125 2825);
PAINT GREEN (-125 2825);
DISPLAY INVISIBLE (-125 2825);
FORCEPROP 1 LAST HDL_TAP TRUE
J 2
(-450 2750);
DISPLAY 1.234043 (-450 2750);
PAINT GREEN (-450 2750);
DISPLAY INVISIBLE (-450 2750);
FORCEPROP 1 LAST PATH I81
J 2
(-123 2875);
DISPLAY 0.872340 (-123 2875);
PAINT GREEN (-123 2875);
DISPLAY INVISIBLE (-123 2875);
FORCEADD TAP..6
R 2
(-125 2975);
FORCEPROP 3 LASTPIN (-175 2975) SIG_NAME M_L_DQ<31>
J 0
(-165 2985);
DISPLAY 0.659574 (-165 2985);
PAINT MONO (-165 2985);
DISPLAY INVISIBLE (-165 2985);
FORCEPROP 1 LASTPIN (-175 2975) BN 31
J 2
(-125 2985);
DISPLAY 0.617021 (-125 2985);
PAINT PINK (-125 2985);
FORCEPROP 2 LAST CDS_LIB mstr_standard
J 2
(-125 2975);
DISPLAY 0.787234 (-125 2975);
PAINT MONO (-125 2975);
DISPLAY INVISIBLE (-125 2975);
FORCEPROP 1 LAST BODY_TYPE PLUMBING
J 2
(-125 2925);
DISPLAY 1.234043 (-125 2925);
PAINT GREEN (-125 2925);
DISPLAY INVISIBLE (-125 2925);
FORCEPROP 1 LAST HDL_TAP TRUE
J 2
(-450 2850);
DISPLAY 1.234043 (-450 2850);
PAINT GREEN (-450 2850);
DISPLAY INVISIBLE (-450 2850);
FORCEPROP 1 LAST PATH I82
J 2
(-123 2975);
DISPLAY 0.872340 (-123 2975);
PAINT GREEN (-123 2975);
DISPLAY INVISIBLE (-123 2975);
FORCEADD TAP..6
R 2
(-125 2925);
FORCEPROP 3 LASTPIN (-175 2925) SIG_NAME M_L_DQ<30>
J 0
(-165 2935);
DISPLAY 0.659574 (-165 2935);
PAINT MONO (-165 2935);
DISPLAY INVISIBLE (-165 2935);
FORCEPROP 1 LASTPIN (-175 2925) BN 30
J 2
(-125 2935);
DISPLAY 0.617021 (-125 2935);
PAINT PINK (-125 2935);
FORCEPROP 2 LAST CDS_LIB mstr_standard
J 2
(-125 2925);
DISPLAY 0.787234 (-125 2925);
PAINT MONO (-125 2925);
DISPLAY INVISIBLE (-125 2925);
FORCEPROP 1 LAST BODY_TYPE PLUMBING
J 2
(-125 2875);
DISPLAY 1.234043 (-125 2875);
PAINT GREEN (-125 2875);
DISPLAY INVISIBLE (-125 2875);
FORCEPROP 1 LAST HDL_TAP TRUE
J 2
(-450 2800);
DISPLAY 1.234043 (-450 2800);
PAINT GREEN (-450 2800);
DISPLAY INVISIBLE (-450 2800);
FORCEPROP 1 LAST PATH I83
J 2
(-123 2925);
DISPLAY 0.872340 (-123 2925);
PAINT GREEN (-123 2925);
DISPLAY INVISIBLE (-123 2925);
FORCEADD TAP..6
R 2
(-125 3175);
FORCEPROP 3 LASTPIN (-175 3175) SIG_NAME M_L_DQ<35>
J 0
(-165 3185);
DISPLAY 0.659574 (-165 3185);
PAINT MONO (-165 3185);
DISPLAY INVISIBLE (-165 3185);
FORCEPROP 1 LASTPIN (-175 3175) BN 35
J 2
(-125 3185);
DISPLAY 0.617021 (-125 3185);
PAINT PINK (-125 3185);
FORCEPROP 2 LAST CDS_LIB mstr_standard
J 2
(-125 3175);
DISPLAY 0.787234 (-125 3175);
PAINT MONO (-125 3175);
DISPLAY INVISIBLE (-125 3175);
FORCEPROP 1 LAST BODY_TYPE PLUMBING
J 2
(-125 3125);
DISPLAY 1.234043 (-125 3125);
PAINT GREEN (-125 3125);
DISPLAY INVISIBLE (-125 3125);
FORCEPROP 1 LAST HDL_TAP TRUE
J 2
(-450 3050);
DISPLAY 1.234043 (-450 3050);
PAINT GREEN (-450 3050);
DISPLAY INVISIBLE (-450 3050);
FORCEPROP 1 LAST PATH I84
J 2
(-123 3175);
DISPLAY 0.872340 (-123 3175);
PAINT GREEN (-123 3175);
DISPLAY INVISIBLE (-123 3175);
FORCEADD TAP..6
R 2
(-125 3125);
FORCEPROP 3 LASTPIN (-175 3125) SIG_NAME M_L_DQ<34>
J 0
(-165 3135);
DISPLAY 0.659574 (-165 3135);
PAINT MONO (-165 3135);
DISPLAY INVISIBLE (-165 3135);
FORCEPROP 1 LASTPIN (-175 3125) BN 34
J 2
(-125 3135);
DISPLAY 0.617021 (-125 3135);
PAINT PINK (-125 3135);
FORCEPROP 2 LAST CDS_LIB mstr_standard
J 2
(-125 3125);
DISPLAY 0.787234 (-125 3125);
PAINT MONO (-125 3125);
DISPLAY INVISIBLE (-125 3125);
FORCEPROP 1 LAST BODY_TYPE PLUMBING
J 2
(-125 3075);
DISPLAY 1.234043 (-125 3075);
PAINT GREEN (-125 3075);
DISPLAY INVISIBLE (-125 3075);
FORCEPROP 1 LAST HDL_TAP TRUE
J 2
(-450 3000);
DISPLAY 1.234043 (-450 3000);
PAINT GREEN (-450 3000);
DISPLAY INVISIBLE (-450 3000);
FORCEPROP 1 LAST PATH I85
J 2
(-123 3125);
DISPLAY 0.872340 (-123 3125);
PAINT GREEN (-123 3125);
DISPLAY INVISIBLE (-123 3125);
FORCEADD TAP..6
R 2
(-125 3225);
FORCEPROP 3 LASTPIN (-175 3225) SIG_NAME M_L_DQ<36>
J 0
(-165 3235);
DISPLAY 0.659574 (-165 3235);
PAINT MONO (-165 3235);
DISPLAY INVISIBLE (-165 3235);
FORCEPROP 1 LASTPIN (-175 3225) BN 36
J 2
(-125 3235);
DISPLAY 0.617021 (-125 3235);
PAINT PINK (-125 3235);
FORCEPROP 2 LAST CDS_LIB mstr_standard
J 2
(-125 3225);
DISPLAY 0.787234 (-125 3225);
PAINT MONO (-125 3225);
DISPLAY INVISIBLE (-125 3225);
FORCEPROP 1 LAST BODY_TYPE PLUMBING
J 2
(-125 3175);
DISPLAY 1.234043 (-125 3175);
PAINT GREEN (-125 3175);
DISPLAY INVISIBLE (-125 3175);
FORCEPROP 1 LAST HDL_TAP TRUE
J 2
(-450 3100);
DISPLAY 1.234043 (-450 3100);
PAINT GREEN (-450 3100);
DISPLAY INVISIBLE (-450 3100);
FORCEPROP 1 LAST PATH I86
J 2
(-123 3225);
DISPLAY 0.872340 (-123 3225);
PAINT GREEN (-123 3225);
DISPLAY INVISIBLE (-123 3225);
FORCEADD TAP..6
R 2
(-125 3075);
FORCEPROP 3 LASTPIN (-175 3075) SIG_NAME M_L_DQ<33>
J 0
(-165 3085);
DISPLAY 0.659574 (-165 3085);
PAINT MONO (-165 3085);
DISPLAY INVISIBLE (-165 3085);
FORCEPROP 1 LASTPIN (-175 3075) BN 33
J 2
(-125 3085);
DISPLAY 0.617021 (-125 3085);
PAINT PINK (-125 3085);
FORCEPROP 2 LAST CDS_LIB mstr_standard
J 2
(-125 3075);
DISPLAY 0.787234 (-125 3075);
PAINT MONO (-125 3075);
DISPLAY INVISIBLE (-125 3075);
FORCEPROP 1 LAST BODY_TYPE PLUMBING
J 2
(-125 3025);
DISPLAY 1.234043 (-125 3025);
PAINT GREEN (-125 3025);
DISPLAY INVISIBLE (-125 3025);
FORCEPROP 1 LAST HDL_TAP TRUE
J 2
(-450 2950);
DISPLAY 1.234043 (-450 2950);
PAINT GREEN (-450 2950);
DISPLAY INVISIBLE (-450 2950);
FORCEPROP 1 LAST PATH I87
J 2
(-123 3075);
DISPLAY 0.872340 (-123 3075);
PAINT GREEN (-123 3075);
DISPLAY INVISIBLE (-123 3075);
FORCEADD TAP..6
R 2
(-125 3025);
FORCEPROP 3 LASTPIN (-175 3025) SIG_NAME M_L_DQ<32>
J 0
(-165 3035);
DISPLAY 0.659574 (-165 3035);
PAINT MONO (-165 3035);
DISPLAY INVISIBLE (-165 3035);
FORCEPROP 1 LASTPIN (-175 3025) BN 32
J 2
(-125 3035);
DISPLAY 0.617021 (-125 3035);
PAINT PINK (-125 3035);
FORCEPROP 2 LAST CDS_LIB mstr_standard
J 2
(-125 3025);
DISPLAY 0.787234 (-125 3025);
PAINT MONO (-125 3025);
DISPLAY INVISIBLE (-125 3025);
FORCEPROP 1 LAST BODY_TYPE PLUMBING
J 2
(-125 2975);
DISPLAY 1.234043 (-125 2975);
PAINT GREEN (-125 2975);
DISPLAY INVISIBLE (-125 2975);
FORCEPROP 1 LAST HDL_TAP TRUE
J 2
(-450 2900);
DISPLAY 1.234043 (-450 2900);
PAINT GREEN (-450 2900);
DISPLAY INVISIBLE (-450 2900);
FORCEPROP 1 LAST PATH I88
J 2
(-123 3025);
DISPLAY 0.872340 (-123 3025);
PAINT GREEN (-123 3025);
DISPLAY INVISIBLE (-123 3025);
FORCEADD TAP..6
R 2
(-125 3325);
FORCEPROP 3 LASTPIN (-175 3325) SIG_NAME M_L_DQ<38>
J 0
(-165 3335);
DISPLAY 0.659574 (-165 3335);
PAINT MONO (-165 3335);
DISPLAY INVISIBLE (-165 3335);
FORCEPROP 1 LASTPIN (-175 3325) BN 38
J 2
(-125 3335);
DISPLAY 0.617021 (-125 3335);
PAINT PINK (-125 3335);
FORCEPROP 2 LAST CDS_LIB mstr_standard
J 2
(-125 3325);
DISPLAY 0.787234 (-125 3325);
PAINT MONO (-125 3325);
DISPLAY INVISIBLE (-125 3325);
FORCEPROP 1 LAST BODY_TYPE PLUMBING
J 2
(-125 3275);
DISPLAY 1.234043 (-125 3275);
PAINT GREEN (-125 3275);
DISPLAY INVISIBLE (-125 3275);
FORCEPROP 1 LAST HDL_TAP TRUE
J 2
(-450 3200);
DISPLAY 1.234043 (-450 3200);
PAINT GREEN (-450 3200);
DISPLAY INVISIBLE (-450 3200);
FORCEPROP 1 LAST PATH I89
J 2
(-123 3325);
DISPLAY 0.872340 (-123 3325);
PAINT GREEN (-123 3325);
DISPLAY INVISIBLE (-123 3325);
FORCEADD OFFPAGE..1
(-2275 1125);
FORCEPROP 2 LAST $XR5 88 
J 0
(-2946 1125);
DISPLAY 0.638298 (-2946 1125);
PAINT MONO (-2946 1125);
FORCEPROP 2 LAST $XR4 87 
J 0
(-2856 1125);
DISPLAY 0.638298 (-2856 1125);
PAINT MONO (-2856 1125);
FORCEPROP 2 LAST $XR3 85 
J 0
(-2766 1125);
DISPLAY 0.638298 (-2766 1125);
PAINT MONO (-2766 1125);
FORCEPROP 2 LAST $XR2 84 
J 0
(-2676 1125);
DISPLAY 0.638298 (-2676 1125);
PAINT MONO (-2676 1125);
FORCEPROP 2 LAST $XR1 83 
J 0
(-2586 1125);
DISPLAY 0.638298 (-2586 1125);
PAINT MONO (-2586 1125);
FORCEPROP 2 LAST $XR0 89 
J 0
(-2496 1125);
DISPLAY 0.638298 (-2496 1125);
PAINT MONO (-2496 1125);
FORCEPROP 2 LAST CDS_LIB mstr_standard
J 0
(-2275 1125);
PAINT ORANGE (-2275 1125);
DISPLAY INVISIBLE (-2275 1125);
FORCEPROP 1 LAST OFFPAGE TRUE
J 0
(-1950 1000);
DISPLAY 0.936170 (-1950 1000);
PAINT GREEN (-1950 1000);
DISPLAY INVISIBLE (-1950 1000);
FORCEPROP 1 LAST COMMENT_BODY TRUE
J 0
(-2150 1025);
DISPLAY 0.936170 (-2150 1025);
PAINT GREEN (-2150 1025);
DISPLAY INVISIBLE (-2150 1025);
FORCEPROP 2 LAST PATH I9
J 0
(-2525 1175);
DISPLAY 1.021277 (-2525 1175);
PAINT ORANGE (-2525 1175);
DISPLAY INVISIBLE (-2525 1175);
FORCEADD TAP..6
R 2
(-125 3275);
FORCEPROP 3 LASTPIN (-175 3275) SIG_NAME M_L_DQ<37>
J 0
(-165 3285);
DISPLAY 0.659574 (-165 3285);
PAINT MONO (-165 3285);
DISPLAY INVISIBLE (-165 3285);
FORCEPROP 1 LASTPIN (-175 3275) BN 37
J 2
(-125 3285);
DISPLAY 0.617021 (-125 3285);
PAINT PINK (-125 3285);
FORCEPROP 2 LAST CDS_LIB mstr_standard
J 2
(-125 3275);
DISPLAY 0.787234 (-125 3275);
PAINT MONO (-125 3275);
DISPLAY INVISIBLE (-125 3275);
FORCEPROP 1 LAST BODY_TYPE PLUMBING
J 2
(-125 3225);
DISPLAY 1.234043 (-125 3225);
PAINT GREEN (-125 3225);
DISPLAY INVISIBLE (-125 3225);
FORCEPROP 1 LAST HDL_TAP TRUE
J 2
(-450 3150);
DISPLAY 1.234043 (-450 3150);
PAINT GREEN (-450 3150);
DISPLAY INVISIBLE (-450 3150);
FORCEPROP 1 LAST PATH I90
J 2
(-123 3275);
DISPLAY 0.872340 (-123 3275);
PAINT GREEN (-123 3275);
DISPLAY INVISIBLE (-123 3275);
FORCEADD TAP..6
R 2
(-125 3425);
FORCEPROP 3 LASTPIN (-175 3425) SIG_NAME M_L_DQ<40>
J 0
(-165 3435);
DISPLAY 0.659574 (-165 3435);
PAINT MONO (-165 3435);
DISPLAY INVISIBLE (-165 3435);
FORCEPROP 1 LASTPIN (-175 3425) BN 40
J 2
(-125 3435);
DISPLAY 0.617021 (-125 3435);
PAINT PINK (-125 3435);
FORCEPROP 2 LAST CDS_LIB mstr_standard
J 2
(-125 3425);
DISPLAY 0.787234 (-125 3425);
PAINT MONO (-125 3425);
DISPLAY INVISIBLE (-125 3425);
FORCEPROP 1 LAST BODY_TYPE PLUMBING
J 2
(-125 3375);
DISPLAY 1.234043 (-125 3375);
PAINT GREEN (-125 3375);
DISPLAY INVISIBLE (-125 3375);
FORCEPROP 1 LAST HDL_TAP TRUE
J 2
(-450 3300);
DISPLAY 1.234043 (-450 3300);
PAINT GREEN (-450 3300);
DISPLAY INVISIBLE (-450 3300);
FORCEPROP 1 LAST PATH I91
J 2
(-123 3425);
DISPLAY 0.872340 (-123 3425);
PAINT GREEN (-123 3425);
DISPLAY INVISIBLE (-123 3425);
FORCEADD TAP..6
R 2
(-125 3375);
FORCEPROP 3 LASTPIN (-175 3375) SIG_NAME M_L_DQ<39>
J 0
(-165 3385);
DISPLAY 0.659574 (-165 3385);
PAINT MONO (-165 3385);
DISPLAY INVISIBLE (-165 3385);
FORCEPROP 1 LASTPIN (-175 3375) BN 39
J 2
(-125 3385);
DISPLAY 0.617021 (-125 3385);
PAINT PINK (-125 3385);
FORCEPROP 2 LAST CDS_LIB mstr_standard
J 2
(-125 3375);
DISPLAY 0.787234 (-125 3375);
PAINT MONO (-125 3375);
DISPLAY INVISIBLE (-125 3375);
FORCEPROP 1 LAST BODY_TYPE PLUMBING
J 2
(-125 3325);
DISPLAY 1.234043 (-125 3325);
PAINT GREEN (-125 3325);
DISPLAY INVISIBLE (-125 3325);
FORCEPROP 1 LAST HDL_TAP TRUE
J 2
(-450 3250);
DISPLAY 1.234043 (-450 3250);
PAINT GREEN (-450 3250);
DISPLAY INVISIBLE (-450 3250);
FORCEPROP 1 LAST PATH I92
J 2
(-123 3375);
DISPLAY 0.872340 (-123 3375);
PAINT GREEN (-123 3375);
DISPLAY INVISIBLE (-123 3375);
FORCEADD TAP..6
R 2
(-125 3475);
FORCEPROP 3 LASTPIN (-175 3475) SIG_NAME M_L_DQ<41>
J 0
(-165 3485);
DISPLAY 0.659574 (-165 3485);
PAINT MONO (-165 3485);
DISPLAY INVISIBLE (-165 3485);
FORCEPROP 1 LASTPIN (-175 3475) BN 41
J 2
(-125 3485);
DISPLAY 0.617021 (-125 3485);
PAINT PINK (-125 3485);
FORCEPROP 2 LAST CDS_LIB mstr_standard
J 2
(-125 3475);
DISPLAY 0.787234 (-125 3475);
PAINT MONO (-125 3475);
DISPLAY INVISIBLE (-125 3475);
FORCEPROP 1 LAST BODY_TYPE PLUMBING
J 2
(-125 3425);
DISPLAY 1.234043 (-125 3425);
PAINT GREEN (-125 3425);
DISPLAY INVISIBLE (-125 3425);
FORCEPROP 1 LAST HDL_TAP TRUE
J 2
(-450 3350);
DISPLAY 1.234043 (-450 3350);
PAINT GREEN (-450 3350);
DISPLAY INVISIBLE (-450 3350);
FORCEPROP 1 LAST PATH I93
J 2
(-123 3475);
DISPLAY 0.872340 (-123 3475);
PAINT GREEN (-123 3475);
DISPLAY INVISIBLE (-123 3475);
FORCEADD TAP..6
R 2
(-125 3625);
FORCEPROP 3 LASTPIN (-175 3625) SIG_NAME M_L_DQ<44>
J 0
(-165 3635);
DISPLAY 0.659574 (-165 3635);
PAINT MONO (-165 3635);
DISPLAY INVISIBLE (-165 3635);
FORCEPROP 1 LASTPIN (-175 3625) BN 44
J 2
(-125 3635);
DISPLAY 0.617021 (-125 3635);
PAINT PINK (-125 3635);
FORCEPROP 2 LAST CDS_LIB mstr_standard
J 2
(-125 3625);
DISPLAY 0.787234 (-125 3625);
PAINT MONO (-125 3625);
DISPLAY INVISIBLE (-125 3625);
FORCEPROP 1 LAST BODY_TYPE PLUMBING
J 2
(-125 3575);
DISPLAY 1.234043 (-125 3575);
PAINT GREEN (-125 3575);
DISPLAY INVISIBLE (-125 3575);
FORCEPROP 1 LAST HDL_TAP TRUE
J 2
(-450 3500);
DISPLAY 1.234043 (-450 3500);
PAINT GREEN (-450 3500);
DISPLAY INVISIBLE (-450 3500);
FORCEPROP 1 LAST PATH I94
J 2
(-123 3625);
DISPLAY 0.872340 (-123 3625);
PAINT GREEN (-123 3625);
DISPLAY INVISIBLE (-123 3625);
FORCEADD TAP..6
R 2
(-125 3675);
FORCEPROP 3 LASTPIN (-175 3675) SIG_NAME M_L_DQ<45>
J 0
(-165 3685);
DISPLAY 0.659574 (-165 3685);
PAINT MONO (-165 3685);
DISPLAY INVISIBLE (-165 3685);
FORCEPROP 1 LASTPIN (-175 3675) BN 45
J 2
(-125 3685);
DISPLAY 0.617021 (-125 3685);
PAINT PINK (-125 3685);
FORCEPROP 2 LAST CDS_LIB mstr_standard
J 2
(-125 3675);
DISPLAY 0.787234 (-125 3675);
PAINT MONO (-125 3675);
DISPLAY INVISIBLE (-125 3675);
FORCEPROP 1 LAST BODY_TYPE PLUMBING
J 2
(-125 3625);
DISPLAY 1.234043 (-125 3625);
PAINT GREEN (-125 3625);
DISPLAY INVISIBLE (-125 3625);
FORCEPROP 1 LAST HDL_TAP TRUE
J 2
(-450 3550);
DISPLAY 1.234043 (-450 3550);
PAINT GREEN (-450 3550);
DISPLAY INVISIBLE (-450 3550);
FORCEPROP 1 LAST PATH I95
J 2
(-123 3675);
DISPLAY 0.872340 (-123 3675);
PAINT GREEN (-123 3675);
DISPLAY INVISIBLE (-123 3675);
FORCEADD TAP..6
R 2
(-125 3725);
FORCEPROP 3 LASTPIN (-175 3725) SIG_NAME M_L_DQ<46>
J 0
(-165 3735);
DISPLAY 0.659574 (-165 3735);
PAINT MONO (-165 3735);
DISPLAY INVISIBLE (-165 3735);
FORCEPROP 1 LASTPIN (-175 3725) BN 46
J 2
(-125 3735);
DISPLAY 0.617021 (-125 3735);
PAINT PINK (-125 3735);
FORCEPROP 2 LAST CDS_LIB mstr_standard
J 2
(-125 3725);
DISPLAY 0.787234 (-125 3725);
PAINT MONO (-125 3725);
DISPLAY INVISIBLE (-125 3725);
FORCEPROP 1 LAST BODY_TYPE PLUMBING
J 2
(-125 3675);
DISPLAY 1.234043 (-125 3675);
PAINT GREEN (-125 3675);
DISPLAY INVISIBLE (-125 3675);
FORCEPROP 1 LAST HDL_TAP TRUE
J 2
(-450 3600);
DISPLAY 1.234043 (-450 3600);
PAINT GREEN (-450 3600);
DISPLAY INVISIBLE (-450 3600);
FORCEPROP 1 LAST PATH I96
J 2
(-123 3725);
DISPLAY 0.872340 (-123 3725);
PAINT GREEN (-123 3725);
DISPLAY INVISIBLE (-123 3725);
FORCEADD TAP..6
R 2
(-125 3575);
FORCEPROP 3 LASTPIN (-175 3575) SIG_NAME M_L_DQ<43>
J 0
(-165 3585);
DISPLAY 0.659574 (-165 3585);
PAINT MONO (-165 3585);
DISPLAY INVISIBLE (-165 3585);
FORCEPROP 1 LASTPIN (-175 3575) BN 43
J 2
(-125 3585);
DISPLAY 0.617021 (-125 3585);
PAINT PINK (-125 3585);
FORCEPROP 2 LAST CDS_LIB mstr_standard
J 2
(-125 3575);
DISPLAY 0.787234 (-125 3575);
PAINT MONO (-125 3575);
DISPLAY INVISIBLE (-125 3575);
FORCEPROP 1 LAST BODY_TYPE PLUMBING
J 2
(-125 3525);
DISPLAY 1.234043 (-125 3525);
PAINT GREEN (-125 3525);
DISPLAY INVISIBLE (-125 3525);
FORCEPROP 1 LAST HDL_TAP TRUE
J 2
(-450 3450);
DISPLAY 1.234043 (-450 3450);
PAINT GREEN (-450 3450);
DISPLAY INVISIBLE (-450 3450);
FORCEPROP 1 LAST PATH I97
J 2
(-123 3575);
DISPLAY 0.872340 (-123 3575);
PAINT GREEN (-123 3575);
DISPLAY INVISIBLE (-123 3575);
FORCEADD TAP..6
R 2
(-125 3525);
FORCEPROP 3 LASTPIN (-175 3525) SIG_NAME M_L_DQ<42>
J 0
(-165 3535);
DISPLAY 0.659574 (-165 3535);
PAINT MONO (-165 3535);
DISPLAY INVISIBLE (-165 3535);
FORCEPROP 1 LASTPIN (-175 3525) BN 42
J 2
(-125 3535);
DISPLAY 0.617021 (-125 3535);
PAINT PINK (-125 3535);
FORCEPROP 2 LAST CDS_LIB mstr_standard
J 2
(-125 3525);
DISPLAY 0.787234 (-125 3525);
PAINT MONO (-125 3525);
DISPLAY INVISIBLE (-125 3525);
FORCEPROP 1 LAST BODY_TYPE PLUMBING
J 2
(-125 3475);
DISPLAY 1.234043 (-125 3475);
PAINT GREEN (-125 3475);
DISPLAY INVISIBLE (-125 3475);
FORCEPROP 1 LAST HDL_TAP TRUE
J 2
(-450 3400);
DISPLAY 1.234043 (-450 3400);
PAINT GREEN (-450 3400);
DISPLAY INVISIBLE (-450 3400);
FORCEPROP 1 LAST PATH I98
J 2
(-123 3525);
DISPLAY 0.872340 (-123 3525);
PAINT GREEN (-123 3525);
DISPLAY INVISIBLE (-123 3525);
FORCEADD PVPP_KLM..1
(675 2750);
FORCEPROP 3 LASTPIN (675 2700) SIG_NAME PVPP_KLM\g
J 0
(685 2710);
DISPLAY 0.659574 (685 2710);
PAINT MONO (685 2710);
DISPLAY INVISIBLE (685 2710);
FORCEPROP 1 LAST VOLTAGE 2.5V
J 0
(630 2707);
DISPLAY 0.340426 (630 2707);
PAINT SKYBLUE (630 2707);
DISPLAY INVISIBLE (630 2707);
FORCEPROP 0 LAST BOM_COST MEM
J 0
(675 2850);
PAINT ORANGE (675 2850);
DISPLAY INVISIBLE (675 2850);
FORCEPROP 2 LAST CDS_LIB mstr_symbols
J 0
(675 2750);
PAINT ORANGE (675 2750);
DISPLAY INVISIBLE (675 2750);
FORCEPROP 1 LAST BODY_TYPE PLUMBING
J 0
(630 2707);
DISPLAY 0.340426 (630 2707);
PAINT GREEN (630 2707);
DISPLAY INVISIBLE (630 2707);
FORCEPROP 1 LAST PATH I99
J 0
(725 2775);
DISPLAY 0.872340 (725 2775);
PAINT AQUA (725 2775);
DISPLAY INVISIBLE (725 2775);
FORCEPROP 2 LAST ROOM DDR4_CH_D
J 0
(675 2850);
PAINT ORANGE (675 2850);
DISPLAY INVISIBLE (675 2850);
FORCEPROP 1 LAST HDL_POWER PVPP_KLM
J 1
(675 2800);
DISPLAY 0.872340 (675 2800);
PAINT GREEN (675 2800);
DISPLAY INVISIBLE (675 2800);
FORCEADD BOM_NOTE..1
(-3375 4925);
FORCEPROP 0 LAST L1 UNSTUFF FOR SKU B
J 0
(-3525 4825);
DISPLAY 1.063830 (-3525 4825);
PAINT WHITE (-3525 4825);
FORCEPROP 2 LAST BOM_COST SB
J 0
(-3525 4900);
DISPLAY 1.361702 (-3525 4900);
PAINT ORANGE (-3525 4900);
DISPLAY INVISIBLE (-3525 4900);
FORCEPROP 2 LAST CDS_LIB mstr_symbols
J 0
(-3375 4925);
PAINT ORANGE (-3375 4925);
DISPLAY INVISIBLE (-3375 4925);
FORCEPROP 1 LAST COMMENT_BODY TRUE
J 0
(-3350 5025);
DISPLAY 1.319149 (-3350 5025);
PAINT ORANGE (-3350 5025);
DISPLAY INVISIBLE (-3350 5025);
FORCEPROP 2 LAST ROOM SB_HEADERS
J 0
(-3525 4900);
DISPLAY 1.361702 (-3525 4900);
PAINT ORANGE (-3525 4900);
DISPLAY INVISIBLE (-3525 4900);
FORCEADD INTEL_CORP_BPAGE..1
(4250 200);
FORCEPROP 1 LAST CDS_CON_LAST_MODIFIED Fri Jun 16 17:48:32 2017
J 0
(2825 525);
PAINT ORANGE (2825 525);
DISPLAY INVISIBLE (2825 525);
FORCEPROP 1 LAST CUSTOM_TXT_CDS <CURRENT_DESIGN_SHEET> OF <TOTAL_DESIGN_SHEETS>
J 0
(3750 225);
PAINT ORANGE (3750 225);
FORCEPROP 1 LAST CUSTOM_TXT_CDS <CON_LAST_MODIFIED>
J 0
(250 300);
PAINT ORANGE (250 300);
FORCEPROP 2 LAST CUSTOM_TXT_CDS <XR_PAGE_TITLE>
J 0
(-3640 5450);
DISPLAY 0.638298 (-3640 5450);
PAINT PINK (-3640 5450);
DISPLAY INVISIBLE (-3640 5450);
FORCEPROP 1 LAST SCH_TITLE CPU1 DDR4 CH L DIMM1
J 0
(-3700 250);
DISPLAY 1.212766 (-3700 250);
PAINT ORANGE (-3700 250);
FORCEPROP 2 LAST PAGE_BORDER TRUE
J 0
(-3640 5450);
DISPLAY 0.638298 (-3640 5450);
PAINT PINK (-3640 5450);
DISPLAY INVISIBLE (-3640 5450);
FORCEPROP 2 LAST CDS_LIB mstr_symbols
J 0
(4250 200);
PAINT MONO (4250 200);
DISPLAY INVISIBLE (4250 200);
FORCEPROP 1 LAST COMMENT_BODY TRUE
J 0
(4262 212);
DISPLAY 0.468085 (4262 212);
PAINT GREEN (4262 212);
DISPLAY INVISIBLE (4262 212);
FORCEPROP 2 LAST CDS_XR_PAGE_TITLE CR-86 : @BASEBOARD_FAB2_LIB.BASEBOARD_FAB2(SCH_1):PAGE86
J 0
(-3640 5450);
DISPLAY 0.638298 (-3640 5450);
PAINT PINK (-3640 5450);
DISPLAY INVISIBLE (-3640 5450);
WIRE 16 -1 (-3525 1725)(-3525 1575);
WIRE 16 -1 (-3525 1725)(-1375 1725);
WIRE 16 -1 (2725 825)(2725 925);
WIRE 16 -1 (2725 925)(2725 975);
WIRE 16 -1 (2725 925)(2925 925);
WIRE 16 -1 (2725 975)(2725 1025);
WIRE 16 -1 (2725 975)(2925 975);
WIRE 16 -1 (2725 1025)(2725 1075);
WIRE 16 -1 (2725 1025)(2925 1025);
WIRE 16 -1 (2725 1075)(2725 1125);
WIRE 16 -1 (2725 1075)(2925 1075);
WIRE 16 -1 (2725 1125)(2725 1175);
WIRE 16 -1 (2725 1125)(2925 1125);
WIRE 16 -1 (2725 1175)(2725 1225);
WIRE 16 -1 (2725 1175)(2925 1175);
WIRE 16 -1 (2725 1225)(2725 1275);
WIRE 16 -1 (2725 1225)(2925 1225);
WIRE 16 -1 (2725 1275)(2725 1325);
WIRE 16 -1 (2725 1275)(2925 1275);
WIRE 16 -1 (2725 1325)(2725 1375);
WIRE 16 -1 (2725 1325)(2925 1325);
WIRE 16 -1 (2725 1375)(2725 1425);
WIRE 16 -1 (2725 1375)(2925 1375);
WIRE 16 -1 (2725 1425)(2725 1475);
WIRE 16 -1 (2725 1425)(2925 1425);
WIRE 16 -1 (2725 1475)(2725 1525);
WIRE 16 -1 (2725 1475)(2925 1475);
WIRE 16 -1 (2725 1525)(2725 1575);
WIRE 16 -1 (2725 1525)(2925 1525);
WIRE 16 -1 (2725 1575)(2725 1625);
WIRE 16 -1 (2725 1575)(2925 1575);
WIRE 16 -1 (2725 1625)(2725 1675);
WIRE 16 -1 (2725 1625)(2925 1625);
WIRE 16 -1 (2725 1675)(2725 1725);
WIRE 16 -1 (2725 1675)(2925 1675);
WIRE 16 -1 (2725 1725)(2725 1775);
WIRE 16 -1 (2725 1725)(2925 1725);
WIRE 16 -1 (2725 1775)(2725 1825);
WIRE 16 -1 (2725 1775)(2925 1775);
WIRE 16 -1 (2725 1825)(2725 1875);
WIRE 16 -1 (2725 1825)(2925 1825);
WIRE 16 -1 (2725 1875)(2725 1925);
WIRE 16 -1 (2725 1875)(2925 1875);
WIRE 16 -1 (2725 1925)(2725 1975);
WIRE 16 -1 (2725 1925)(2925 1925);
WIRE 16 -1 (2725 1975)(2725 2025);
WIRE 16 -1 (2725 1975)(2925 1975);
WIRE 16 -1 (2725 2025)(2725 2075);
WIRE 16 -1 (2725 2025)(2925 2025);
WIRE 16 -1 (2725 2075)(2725 2125);
WIRE 16 -1 (2725 2075)(2925 2075);
WIRE 16 -1 (2725 2125)(2725 2175);
WIRE 16 -1 (2725 2125)(2925 2125);
WIRE 16 -1 (2725 2175)(2725 2225);
WIRE 16 -1 (2725 2175)(2925 2175);
WIRE 16 -1 (2725 2225)(2725 2275);
WIRE 16 -1 (2725 2225)(2925 2225);
WIRE 16 -1 (2725 2275)(2725 2325);
WIRE 16 -1 (2725 2275)(2925 2275);
WIRE 16 -1 (2725 2325)(2725 2375);
WIRE 16 -1 (2725 2325)(2925 2325);
WIRE 16 -1 (2725 2375)(2725 2425);
WIRE 16 -1 (2725 2375)(2925 2375);
WIRE 16 -1 (2725 2425)(2725 2475);
WIRE 16 -1 (2725 2425)(2925 2425);
WIRE 16 -1 (2725 2475)(2725 2525);
WIRE 16 -1 (2725 2475)(2925 2475);
WIRE 16 -1 (2725 2525)(2725 2575);
WIRE 16 -1 (2725 2525)(2925 2525);
WIRE 16 -1 (2725 2575)(2725 2625);
WIRE 16 -1 (2725 2575)(2925 2575);
WIRE 16 -1 (2725 2625)(2725 2675);
WIRE 16 -1 (2725 2625)(2925 2625);
WIRE 16 -1 (2725 2675)(2725 2725);
WIRE 16 -1 (2725 2675)(2925 2675);
WIRE 16 -1 (2725 2725)(2725 2775);
WIRE 16 -1 (2725 2725)(2925 2725);
WIRE 16 -1 (2725 2775)(2725 2825);
WIRE 16 -1 (2725 2775)(2925 2775);
WIRE 16 -1 (2725 2825)(2725 2875);
WIRE 16 -1 (2725 2825)(2925 2825);
WIRE 16 -1 (2725 2875)(2725 2925);
WIRE 16 -1 (2725 2875)(2925 2875);
WIRE 16 -1 (2725 2925)(2725 2975);
WIRE 16 -1 (2725 2925)(2925 2925);
WIRE 16 -1 (2725 2975)(2725 3025);
WIRE 16 -1 (2725 2975)(2925 2975);
WIRE 16 -1 (2725 3025)(2725 3075);
WIRE 16 -1 (2725 3025)(2925 3025);
WIRE 16 -1 (2725 3075)(2725 3125);
WIRE 16 -1 (2725 3075)(2925 3075);
WIRE 16 -1 (2725 3125)(2725 3175);
WIRE 16 -1 (2725 3125)(2925 3125);
WIRE 16 -1 (2725 3175)(2725 3225);
WIRE 16 -1 (2725 3175)(2925 3175);
WIRE 16 -1 (2725 3225)(2925 3225);
WIRE 16 -1 (4125 825)(4125 925);
WIRE 16 -1 (4125 925)(4125 975);
WIRE 16 -1 (4125 925)(3925 925);
WIRE 16 -1 (4125 975)(4125 1025);
WIRE 16 -1 (4125 975)(3925 975);
WIRE 16 -1 (4125 1025)(4125 1075);
WIRE 16 -1 (4125 1025)(3925 1025);
WIRE 16 -1 (4125 1075)(4125 1125);
WIRE 16 -1 (4125 1075)(3925 1075);
WIRE 16 -1 (4125 1125)(4125 1175);
WIRE 16 -1 (4125 1125)(3925 1125);
WIRE 16 -1 (4125 1175)(4125 1225);
WIRE 16 -1 (4125 1175)(3925 1175);
WIRE 16 -1 (4125 1225)(4125 1275);
WIRE 16 -1 (4125 1225)(3925 1225);
WIRE 16 -1 (4125 1275)(4125 1325);
WIRE 16 -1 (4125 1275)(3925 1275);
WIRE 16 -1 (4125 1325)(4125 1375);
WIRE 16 -1 (4125 1325)(3925 1325);
WIRE 16 -1 (4125 1375)(4125 1425);
WIRE 16 -1 (4125 1375)(3925 1375);
WIRE 16 -1 (4125 1425)(4125 1475);
WIRE 16 -1 (4125 1425)(3925 1425);
WIRE 16 -1 (4125 1475)(4125 1525);
WIRE 16 -1 (4125 1475)(3925 1475);
WIRE 16 -1 (4125 1525)(4125 1575);
WIRE 16 -1 (4125 1525)(3925 1525);
WIRE 16 -1 (4125 1575)(4125 1625);
WIRE 16 -1 (4125 1575)(3925 1575);
WIRE 16 -1 (4125 1625)(4125 1675);
WIRE 16 -1 (4125 1625)(3925 1625);
WIRE 16 -1 (4125 1675)(4125 1725);
WIRE 16 -1 (4125 1675)(3925 1675);
WIRE 16 -1 (4125 1725)(4125 1775);
WIRE 16 -1 (4125 1725)(3925 1725);
WIRE 16 -1 (4125 1775)(4125 1825);
WIRE 16 -1 (4125 1775)(3925 1775);
WIRE 16 -1 (4125 1825)(4125 1875);
WIRE 16 -1 (4125 1825)(3925 1825);
WIRE 16 -1 (4125 1875)(4125 1925);
WIRE 16 -1 (4125 1875)(3925 1875);
WIRE 16 -1 (4125 1925)(4125 1975);
WIRE 16 -1 (4125 1925)(3925 1925);
WIRE 16 -1 (4125 1975)(4125 2025);
WIRE 16 -1 (4125 1975)(3925 1975);
WIRE 16 -1 (4125 2025)(4125 2075);
WIRE 16 -1 (4125 2025)(3925 2025);
WIRE 16 -1 (4125 2075)(4125 2125);
WIRE 16 -1 (4125 2075)(3925 2075);
WIRE 16 -1 (4125 2125)(4125 2175);
WIRE 16 -1 (4125 2125)(3925 2125);
WIRE 16 -1 (4125 2175)(4125 2225);
WIRE 16 -1 (4125 2175)(3925 2175);
WIRE 16 -1 (4125 2225)(4125 2275);
WIRE 16 -1 (4125 2225)(3925 2225);
WIRE 16 -1 (4125 2275)(4125 2325);
WIRE 16 -1 (4125 2275)(3925 2275);
WIRE 16 -1 (4125 2325)(4125 2375);
WIRE 16 -1 (4125 2325)(3925 2325);
WIRE 16 -1 (4125 2375)(4125 2425);
WIRE 16 -1 (4125 2375)(3925 2375);
WIRE 16 -1 (4125 2425)(4125 2475);
WIRE 16 -1 (4125 2425)(3925 2425);
WIRE 16 -1 (4125 2475)(4125 2525);
WIRE 16 -1 (4125 2475)(3925 2475);
WIRE 16 -1 (4125 2525)(4125 2575);
WIRE 16 -1 (4125 2525)(3925 2525);
WIRE 16 -1 (4125 2575)(4125 2625);
WIRE 16 -1 (4125 2575)(3925 2575);
WIRE 16 -1 (4125 2625)(4125 2675);
WIRE 16 -1 (4125 2625)(3925 2625);
WIRE 16 -1 (4125 2675)(4125 2725);
WIRE 16 -1 (4125 2675)(3925 2675);
WIRE 16 -1 (4125 2725)(4125 2775);
WIRE 16 -1 (4125 2725)(3925 2725);
WIRE 16 -1 (4125 2775)(4125 2825);
WIRE 16 -1 (4125 2775)(3925 2775);
WIRE 16 -1 (4125 2825)(4125 2875);
WIRE 16 -1 (4125 2825)(3925 2825);
WIRE 16 -1 (4125 2875)(4125 2925);
WIRE 16 -1 (4125 2875)(3925 2875);
WIRE 16 -1 (4125 2925)(4125 2975);
WIRE 16 -1 (4125 2925)(3925 2925);
WIRE 16 -1 (4125 2975)(4125 3025);
WIRE 16 -1 (4125 2975)(3925 2975);
WIRE 16 -1 (4125 3025)(4125 3075);
WIRE 16 -1 (4125 3025)(3925 3025);
WIRE 16 -1 (4125 3075)(4125 3125);
WIRE 16 -1 (4125 3075)(3925 3075);
WIRE 16 -1 (4125 3125)(4125 3175);
WIRE 16 -1 (4125 3125)(3925 3125);
WIRE 16 -1 (4125 3175)(4125 3225);
WIRE 16 -1 (4125 3175)(3925 3175);
WIRE 16 -1 (4125 3225)(3925 3225);
WIRE 16 -1 (2000 2575)(2000 2650);
WIRE 16 -1 (2000 2525)(2000 2575);
WIRE 16 -1 (1875 2575)(2000 2575);
WIRE 16 -1 (1875 2525)(2000 2525);
WIRE 16 -1 (-3025 1125)(-3025 1025);
WIRE 16 -1 (-3525 1775)(-3525 1875);
WIRE 16 -1 (-3525 1775)(-1475 1775);
WIRE 16 -1 (-1475 1675)(-1475 1775);
WIRE 16 -1 (-1475 1775)(-1375 1775);
WIRE 16 -1 (-1475 1625)(-1475 1675);
WIRE 16 -1 (-1475 1675)(-1375 1675);
WIRE 16 -1 (-1375 1625)(-1475 1625);
WIRE 16 -1 (275 2225)(275 2125);
WIRE 16 -1 (275 2125)(675 2125);
WIRE 16 -1 (675 2075)(675 2125);
WIRE 16 -1 (675 2125)(875 2125);
WIRE 16 -1 (675 2025)(675 2075);
WIRE 16 -1 (675 2075)(875 2075);
WIRE 16 -1 (675 1975)(675 2025);
WIRE 16 -1 (675 2025)(875 2025);
WIRE 16 -1 (675 1925)(675 1975);
WIRE 16 -1 (675 1975)(875 1975);
WIRE 16 -1 (675 1875)(675 1925);
WIRE 16 -1 (675 1925)(875 1925);
WIRE 16 -1 (675 1825)(675 1875);
WIRE 16 -1 (675 1875)(875 1875);
WIRE 16 -1 (675 1775)(675 1825);
WIRE 16 -1 (675 1825)(875 1825);
WIRE 16 -1 (675 1725)(675 1775);
WIRE 16 -1 (675 1775)(875 1775);
WIRE 16 -1 (675 1675)(675 1725);
WIRE 16 -1 (675 1725)(875 1725);
WIRE 16 -1 (675 1625)(675 1675);
WIRE 16 -1 (675 1675)(875 1675);
WIRE 16 -1 (675 1575)(675 1625);
WIRE 16 -1 (675 1625)(875 1625);
WIRE 16 -1 (675 1525)(675 1575);
WIRE 16 -1 (675 1575)(875 1575);
WIRE 16 -1 (675 1475)(675 1525);
WIRE 16 -1 (675 1525)(875 1525);
WIRE 16 -1 (675 1425)(675 1475);
WIRE 16 -1 (675 1475)(875 1475);
WIRE 16 -1 (675 1375)(675 1425);
WIRE 16 -1 (675 1425)(875 1425);
WIRE 16 -1 (675 1325)(675 1375);
WIRE 16 -1 (675 1375)(875 1375);
WIRE 16 -1 (675 1275)(675 1325);
WIRE 16 -1 (675 1325)(875 1325);
WIRE 16 -1 (675 1225)(675 1275);
WIRE 16 -1 (675 1275)(875 1275);
WIRE 16 -1 (675 1175)(675 1225);
WIRE 16 -1 (675 1225)(875 1225);
WIRE 16 -1 (675 1125)(675 1175);
WIRE 16 -1 (675 1175)(875 1175);
WIRE 16 -1 (675 1075)(675 1125);
WIRE 16 -1 (675 1125)(875 1125);
WIRE 16 -1 (675 1025)(675 1075);
WIRE 16 -1 (675 1075)(875 1075);
WIRE 16 -1 (675 975)(675 1025);
WIRE 16 -1 (675 1025)(875 1025);
WIRE 16 -1 (675 925)(675 975);
WIRE 16 -1 (675 975)(875 975);
WIRE 16 -1 (675 875)(675 925);
WIRE 16 -1 (675 925)(875 925);
WIRE 16 -1 (675 875)(875 875);
WIRE 16 -1 (525 2375)(525 2275);
WIRE 16 -1 (525 2275)(675 2275);
WIRE 16 -1 (675 2225)(675 2275);
WIRE 16 -1 (675 2275)(875 2275);
WIRE 16 -1 (675 2225)(875 2225);
WIRE 16 -1 (675 2700)(675 2575);
WIRE 16 -1 (675 2575)(675 2525);
WIRE 16 -1 (675 2575)(875 2575);
WIRE 16 -1 (675 2475)(675 2525);
WIRE 16 -1 (675 2525)(875 2525);
WIRE 16 -1 (675 2475)(675 2425);
WIRE 16 -1 (675 2475)(875 2475);
WIRE 16 -1 (675 2425)(675 2375);
WIRE 16 -1 (675 2425)(875 2425);
WIRE 16 -1 (675 2375)(875 2375);
WIRE 17 -1 (400 4625)(-75 4625);
FORCEPROP 2 LAST SIG_NAME M_L_DQ<63:0>
J 0
(-35 4635);
DISPLAY 0.617021 (-35 4635);
PAINT ORANGE (-35 4635);
WIRE 17 -1 (-75 4625)(-75 4600);
WIRE 17 -1 (-75 4550)(-75 4600);
WIRE 17 -1 (-75 4500)(-75 4550);
WIRE 17 -1 (-75 4450)(-75 4500);
WIRE 17 -1 (-75 4400)(-75 4450);
WIRE 17 -1 (-75 4350)(-75 4400);
WIRE 17 -1 (-75 4300)(-75 4350);
WIRE 17 -1 (-75 4250)(-75 4300);
WIRE 17 -1 (-75 4200)(-75 4250);
WIRE 17 -1 (-75 4150)(-75 4200);
WIRE 17 -1 (-75 4100)(-75 4150);
WIRE 17 -1 (-75 4050)(-75 4100);
WIRE 17 -1 (-75 4000)(-75 4050);
WIRE 17 -1 (-75 3950)(-75 4000);
WIRE 17 -1 (-75 3900)(-75 3950);
WIRE 17 -1 (-75 3850)(-75 3900);
WIRE 17 -1 (-75 3800)(-75 3850);
WIRE 17 -1 (-75 3750)(-75 3800);
WIRE 17 -1 (-75 3700)(-75 3750);
WIRE 17 -1 (-75 3650)(-75 3700);
WIRE 17 -1 (-75 3600)(-75 3650);
WIRE 17 -1 (-75 3550)(-75 3600);
WIRE 17 -1 (-75 3500)(-75 3550);
WIRE 17 -1 (-75 3450)(-75 3500);
WIRE 17 -1 (-75 3400)(-75 3450);
WIRE 17 -1 (-75 3350)(-75 3400);
WIRE 17 -1 (-75 3300)(-75 3350);
WIRE 17 -1 (-75 3250)(-75 3300);
WIRE 17 -1 (-75 3200)(-75 3250);
WIRE 17 -1 (-75 3150)(-75 3200);
WIRE 17 -1 (-75 3100)(-75 3150);
WIRE 17 -1 (-75 3050)(-75 3100);
WIRE 17 -1 (-75 3000)(-75 3050);
WIRE 17 -1 (-75 2950)(-75 3000);
WIRE 17 -1 (-75 2900)(-75 2950);
WIRE 17 -1 (-75 2850)(-75 2900);
WIRE 17 -1 (-75 2800)(-75 2850);
WIRE 17 -1 (-75 2750)(-75 2800);
WIRE 17 -1 (-75 2700)(-75 2750);
WIRE 17 -1 (-75 2650)(-75 2700);
WIRE 17 -1 (-75 2600)(-75 2650);
WIRE 17 -1 (-75 2550)(-75 2600);
WIRE 17 -1 (-75 2500)(-75 2550);
WIRE 17 -1 (-75 2450)(-75 2500);
WIRE 17 -1 (-75 2400)(-75 2450);
WIRE 17 -1 (-75 2350)(-75 2400);
WIRE 17 -1 (-75 2300)(-75 2350);
WIRE 17 -1 (-75 2250)(-75 2300);
WIRE 17 -1 (-75 2200)(-75 2250);
WIRE 17 -1 (-75 2150)(-75 2200);
WIRE 17 -1 (-75 2100)(-75 2150);
WIRE 17 -1 (-75 2050)(-75 2100);
WIRE 17 -1 (-75 2000)(-75 2050);
WIRE 17 -1 (-75 1950)(-75 2000);
WIRE 17 -1 (-75 1900)(-75 1950);
WIRE 17 -1 (-75 1850)(-75 1900);
WIRE 17 -1 (-75 1800)(-75 1850);
WIRE 17 -1 (-75 1750)(-75 1800);
WIRE 17 -1 (-75 1700)(-75 1750);
WIRE 17 -1 (-75 1650)(-75 1700);
WIRE 17 -1 (-75 1600)(-75 1650);
WIRE 17 -1 (-75 1550)(-75 1600);
WIRE 17 -1 (-75 1450)(-75 1500);
WIRE 17 -1 (-75 1500)(-75 1550);
WIRE 17 -1 (-1675 2950)(-1675 3000);
WIRE 17 -1 (-1675 3125)(-2175 3125);
FORCEPROP 2 LAST SIG_NAME M_L_CS_N<7:0>
J 0
(-2150 3135);
DISPLAY 0.617021 (-2150 3135);
PAINT ORANGE (-2150 3135);
WIRE 17 -1 (-1675 3100)(-1675 3125);
WIRE 17 -1 (-1675 3000)(-1675 3050);
WIRE 17 -1 (-1675 3050)(-1675 3100);
WIRE 17 -1 (-1675 2200)(-1675 2250);
WIRE 17 -1 (-1675 2250)(-1675 2300);
WIRE 17 -1 (-1675 2575)(-2175 2575);
FORCEPROP 2 LAST SIG_NAME M_L_ECC<7:0>
J 0
(-2150 2585);
DISPLAY 0.617021 (-2150 2585);
PAINT ORANGE (-2150 2585);
WIRE 17 -1 (-1675 2300)(-1675 2350);
WIRE 17 -1 (-1675 2350)(-1675 2400);
WIRE 17 -1 (-1675 2550)(-1675 2575);
WIRE 17 -1 (-1675 2500)(-1675 2550);
WIRE 17 -1 (-1675 2400)(-1675 2450);
WIRE 17 -1 (-1675 2450)(-1675 2500);
WIRE 17 -1 (-1675 2875)(-2175 2875);
FORCEPROP 2 LAST SIG_NAME M_L_CKE<3:0>
J 0
(-2150 2885);
DISPLAY 0.617021 (-2150 2885);
PAINT ORANGE (-2150 2885);
WIRE 17 -1 (-1675 2800)(-1675 2850);
WIRE 17 -1 (-1675 2850)(-1675 2875);
WIRE 17 -1 (-1675 2725)(-2175 2725);
FORCEPROP 2 LAST SIG_NAME M_L_ODT<3:0>
J 0
(-2150 2735);
DISPLAY 0.617021 (-2150 2735);
PAINT ORANGE (-2150 2735);
WIRE 17 -1 (-1675 2700)(-1675 2725);
WIRE 17 -1 (-1675 2650)(-1675 2700);
WIRE 17 -1 (-1675 3675)(-2175 3675);
FORCEPROP 2 LAST SIG_NAME M_L_BA<1:0>
J 0
(-2150 3685);
DISPLAY 0.617021 (-2150 3685);
PAINT ORANGE (-2150 3685);
WIRE 17 -1 (-1675 3675)(-1675 3650);
WIRE 17 -1 (-1675 3600)(-1675 3650);
WIRE 17 -1 (-2175 4625)(-1675 4625);
FORCEPROP 2 LAST SIG_NAME M_L_MA<17:0>
J 0
(-2150 4635);
DISPLAY 0.617021 (-2150 4635);
PAINT ORANGE (-2150 4635);
WIRE 17 -1 (-1675 4600)(-1675 4625);
WIRE 17 -1 (-1675 4550)(-1675 4600);
WIRE 17 -1 (-1675 4500)(-1675 4550);
WIRE 17 -1 (-1675 4450)(-1675 4500);
WIRE 17 -1 (-1675 4400)(-1675 4450);
WIRE 17 -1 (-1675 4350)(-1675 4400);
WIRE 17 -1 (-1675 4300)(-1675 4350);
WIRE 17 -1 (-1675 4250)(-1675 4300);
WIRE 17 -1 (-1675 4200)(-1675 4250);
WIRE 17 -1 (-1675 4150)(-1675 4200);
WIRE 17 -1 (-1675 4100)(-1675 4150);
WIRE 17 -1 (-1675 4050)(-1675 4100);
WIRE 17 -1 (-1675 4000)(-1675 4050);
WIRE 17 -1 (-1675 3950)(-1675 4000);
WIRE 17 -1 (-1675 3900)(-1675 3950);
WIRE 17 -1 (-1675 3850)(-1675 3900);
WIRE 17 -1 (-1675 3800)(-1675 3850);
WIRE 17 -1 (-1675 3750)(-1675 3800);
WIRE 17 -1 (-1675 3550)(-2175 3550);
FORCEPROP 2 LAST SIG_NAME M_L_BG<1:0>
J 0
(-2150 3560);
DISPLAY 0.617021 (-2150 3560);
PAINT ORANGE (-2150 3560);
WIRE 17 -1 (-1675 3500)(-1675 3550);
WIRE 17 -1 (-1675 3425)(-2175 3425);
FORCEPROP 2 LAST SIG_NAME M_L_CLK_DP<3:0>
J 0
(-2175 3435);
DISPLAY 0.617021 (-2175 3435);
PAINT ORANGE (-2175 3435);
WIRE 17 -1 (-1675 3400)(-1675 3425);
WIRE 17 -1 (-1675 3300)(-1675 3400);
WIRE 17 -1 (-1875 3350)(-1875 3250);
WIRE 17 -1 (-1875 3375)(-2175 3375);
FORCEPROP 2 LAST SIG_NAME M_L_CLK_DN<3:0>
J 0
(-2175 3385);
DISPLAY 0.617021 (-2175 3385);
PAINT ORANGE (-2175 3385);
WIRE 17 -1 (-1875 3375)(-1875 3350);
WIRE 17 -1 (3175 4875)(2375 4875);
FORCEPROP 2 LAST SIG_NAME M_L_DQS_DP<17:0>
J 0
(2625 4885);
DISPLAY 0.617021 (2625 4885);
PAINT ORANGE (2625 4885);
WIRE 17 -1 (2375 4850)(2375 4875);
WIRE 17 -1 (2375 4750)(2375 4850);
WIRE 17 -1 (2375 4650)(2375 4750);
WIRE 17 -1 (2375 4550)(2375 4650);
WIRE 17 -1 (2375 4450)(2375 4550);
WIRE 17 -1 (2375 4350)(2375 4450);
WIRE 17 -1 (2375 4250)(2375 4350);
WIRE 17 -1 (2375 4150)(2375 4250);
WIRE 17 -1 (2375 4050)(2375 4150);
WIRE 17 -1 (2375 3950)(2375 4050);
WIRE 17 -1 (2375 3850)(2375 3950);
WIRE 17 -1 (2375 3750)(2375 3850);
WIRE 17 -1 (2375 3650)(2375 3750);
WIRE 17 -1 (2375 3550)(2375 3650);
WIRE 17 -1 (2375 3450)(2375 3550);
WIRE 17 -1 (2375 3350)(2375 3450);
WIRE 17 -1 (2375 3250)(2375 3350);
WIRE 17 -1 (2375 3150)(2375 3250);
WIRE 17 -1 (3175 4825)(2575 4825);
FORCEPROP 2 LAST SIG_NAME M_L_DQS_DN<17:0>
J 0
(2625 4835);
DISPLAY 0.617021 (2625 4835);
PAINT ORANGE (2625 4835);
WIRE 17 -1 (2575 4800)(2575 4825);
WIRE 17 -1 (2575 4700)(2575 4800);
WIRE 17 -1 (2575 4600)(2575 4700);
WIRE 17 -1 (2575 4500)(2575 4600);
WIRE 17 -1 (2575 4400)(2575 4500);
WIRE 17 -1 (2575 4300)(2575 4400);
WIRE 17 -1 (2575 4200)(2575 4300);
WIRE 17 -1 (2575 4100)(2575 4200);
WIRE 17 -1 (2575 4000)(2575 4100);
WIRE 17 -1 (2575 3900)(2575 4000);
WIRE 17 -1 (2575 3800)(2575 3900);
WIRE 17 -1 (2575 3700)(2575 3800);
WIRE 17 -1 (2575 3600)(2575 3700);
WIRE 17 -1 (2575 3500)(2575 3600);
WIRE 17 -1 (2575 3400)(2575 3500);
WIRE 17 -1 (2575 3300)(2575 3400);
WIRE 17 -1 (2575 3200)(2575 3300);
WIRE 17 -1 (2575 3100)(2575 3200);
WIRE 16 -1 (2475 4575)(2075 4575);
WIRE 16 -1 (2275 4525)(2075 4525);
WIRE 16 -1 (2475 4475)(2075 4475);
WIRE 16 -1 (2275 4425)(2075 4425);
WIRE 16 -1 (2475 4375)(2075 4375);
WIRE 16 -1 (2275 4325)(2075 4325);
WIRE 16 -1 (2475 4275)(2075 4275);
WIRE 16 -1 (2475 4175)(2075 4175);
WIRE 16 -1 (2275 4125)(2075 4125);
WIRE 16 -1 (2475 3475)(2075 3475);
WIRE 16 -1 (2275 3425)(2075 3425);
WIRE 16 -1 (2475 3375)(2075 3375);
WIRE 16 -1 (2275 3325)(2075 3325);
WIRE 16 -1 (2475 3275)(2075 3275);
WIRE 16 -1 (2275 3225)(2075 3225);
WIRE 16 -1 (2475 3175)(2075 3175);
WIRE 16 -1 (-175 4525)(-375 4525);
WIRE 16 -1 (-175 4475)(-375 4475);
WIRE 16 -1 (-175 4125)(-375 4125);
WIRE 16 -1 (2275 4225)(2075 4225);
WIRE 16 -1 (2275 4025)(2075 4025);
WIRE 16 -1 (2475 4075)(2075 4075);
WIRE 16 -1 (2475 3975)(2075 3975);
WIRE 16 -1 (2475 3875)(2075 3875);
WIRE 16 -1 (2475 3775)(2075 3775);
WIRE 16 -1 (2475 3675)(2075 3675);
WIRE 16 -1 (2475 3575)(2075 3575);
WIRE 16 -1 (2475 4775)(2075 4775);
WIRE 16 -1 (2475 4675)(2075 4675);
WIRE 16 -1 (2275 4825)(2075 4825);
WIRE 16 -1 (2275 4725)(2075 4725);
WIRE 16 -1 (2275 4625)(2075 4625);
WIRE 16 -1 (2275 3925)(2075 3925);
WIRE 16 -1 (2275 3825)(2075 3825);
WIRE 16 -1 (2275 3725)(2075 3725);
WIRE 16 -1 (2275 3625)(2075 3625);
WIRE 16 -1 (2475 3075)(2075 3075);
WIRE 16 -1 (2275 3525)(2075 3525);
WIRE 16 -1 (2275 3125)(2075 3125);
WIRE 16 -1 (-175 4325)(-375 4325);
WIRE 16 -1 (-175 4275)(-375 4275);
WIRE 16 -1 (-175 4175)(-375 4175);
WIRE 16 -1 (-175 4225)(-375 4225);
WIRE 16 -1 (-175 4375)(-375 4375);
WIRE 16 -1 (-175 4425)(-375 4425);
WIRE 16 -1 (-175 4575)(-375 4575);
WIRE 16 -1 (-1375 4525)(-1575 4525);
WIRE 16 -1 (-1375 4475)(-1575 4475);
WIRE 16 -1 (-1375 4425)(-1575 4425);
WIRE 16 -1 (-1375 4275)(-1575 4275);
WIRE 16 -1 (-1375 4225)(-1575 4225);
WIRE 16 -1 (-1375 4175)(-1575 4175);
WIRE 16 -1 (-1375 4125)(-1575 4125);
WIRE 16 -1 (-1375 4575)(-1575 4575);
WIRE 16 -1 (-1375 4375)(-1575 4375);
WIRE 16 -1 (-1375 4325)(-1575 4325);
WIRE 16 -1 (-175 3775)(-375 3775);
WIRE 16 -1 (-175 3825)(-375 3825);
WIRE 16 -1 (-175 3875)(-375 3875);
WIRE 16 -1 (-175 3925)(-375 3925);
WIRE 16 -1 (-175 3975)(-375 3975);
WIRE 16 -1 (-175 4025)(-375 4025);
WIRE 16 -1 (-175 4075)(-375 4075);
WIRE 16 -1 (-175 3625)(-375 3625);
WIRE 16 -1 (-175 3675)(-375 3675);
WIRE 16 -1 (-175 3725)(-375 3725);
WIRE 16 -1 (-175 3325)(-375 3325);
WIRE 16 -1 (-175 3225)(-375 3225);
WIRE 16 -1 (-175 3175)(-375 3175);
WIRE 16 -1 (-175 3075)(-375 3075);
WIRE 16 -1 (-175 3125)(-375 3125);
WIRE 16 -1 (-175 3275)(-375 3275);
WIRE 16 -1 (-175 3375)(-375 3375);
WIRE 16 -1 (-175 3425)(-375 3425);
WIRE 16 -1 (-175 3475)(-375 3475);
WIRE 16 -1 (-175 3525)(-375 3525);
WIRE 16 -1 (-175 3575)(-375 3575);
WIRE 16 -1 (-175 2725)(-375 2725);
WIRE 16 -1 (-175 2775)(-375 2775);
WIRE 16 -1 (-175 2575)(-375 2575);
WIRE 16 -1 (-175 2625)(-375 2625);
WIRE 16 -1 (-175 2675)(-375 2675);
WIRE 16 -1 (-175 2925)(-375 2925);
WIRE 16 -1 (-175 2975)(-375 2975);
WIRE 16 -1 (-175 3025)(-375 3025);
WIRE 16 -1 (-175 2825)(-375 2825);
WIRE 16 -1 (-175 2875)(-375 2875);
WIRE 16 -1 (-175 2275)(-375 2275);
WIRE 16 -1 (-175 2175)(-375 2175);
WIRE 16 -1 (-175 2075)(-375 2075);
WIRE 16 -1 (-175 2125)(-375 2125);
WIRE 16 -1 (-175 2225)(-375 2225);
WIRE 16 -1 (-175 2325)(-375 2325);
WIRE 16 -1 (-175 2375)(-375 2375);
WIRE 16 -1 (-175 2425)(-375 2425);
WIRE 16 -1 (-175 2475)(-375 2475);
WIRE 16 -1 (-175 2525)(-375 2525);
WIRE 16 -1 (-1375 3225)(-1775 3225);
WIRE 16 -1 (-1375 3325)(-1775 3325);
WIRE 16 -1 (-1375 3375)(-1575 3375);
WIRE 16 -1 (-1375 3275)(-1575 3275);
WIRE 16 -1 (-1375 3475)(-1575 3475);
WIRE 16 -1 (-1375 3825)(-1575 3825);
WIRE 16 -1 (-1375 3575)(-1575 3575);
WIRE 16 -1 (-1375 3525)(-1575 3525);
WIRE 16 -1 (-1375 4075)(-1575 4075);
WIRE 16 -1 (-1375 4025)(-1575 4025);
WIRE 16 -1 (-1375 3975)(-1575 3975);
WIRE 16 -1 (-1375 3925)(-1575 3925);
WIRE 16 -1 (-1375 3875)(-1575 3875);
WIRE 16 -1 (-1375 3775)(-1575 3775);
WIRE 16 -1 (-1375 3725)(-1575 3725);
WIRE 16 -1 (-1375 3075)(-1575 3075);
WIRE 16 -1 (-1375 3625)(-1575 3625);
WIRE 16 -1 (-1550 3175)(-2175 3175);
FORCEPROP 2 LAST SIG_NAME M_L_C<2>
J 0
(-2150 3185);
DISPLAY 0.617021 (-2150 3185);
PAINT ORANGE (-2150 3185);
WIRE 16 -1 (-1550 3175)(-1550 3125);
WIRE 16 -1 (-1550 3125)(-1375 3125);
WIRE 16 -1 (-1375 2925)(-1575 2925);
WIRE 16 -1 (-1375 2775)(-1575 2775);
WIRE 16 -1 (-1375 2675)(-1575 2675);
WIRE 16 -1 (-1375 2625)(-1575 2625);
WIRE 16 -1 (-1375 2525)(-1575 2525);
WIRE 16 -1 (-1375 2825)(-1575 2825);
WIRE 16 -1 (-1375 2175)(-1575 2175);
WIRE 16 -1 (-1375 2225)(-1575 2225);
WIRE 16 -1 (-1375 2275)(-1575 2275);
WIRE 16 -1 (-1375 2325)(-1575 2325);
WIRE 16 -1 (-1375 2375)(-1575 2375);
WIRE 16 -1 (-1375 2425)(-1575 2425);
WIRE 16 -1 (-1375 2475)(-1575 2475);
WIRE 16 -1 (-1375 2975)(-1575 2975);
WIRE 16 -1 (-1375 3025)(-1575 3025);
WIRE 16 -1 (-1725 2525)(-2175 2525);
FORCEPROP 2 LAST SIG_NAME M_L_PAR
J 0
(-2150 2535);
DISPLAY 0.617021 (-2150 2535);
PAINT ORANGE (-2150 2535);
WIRE 16 -1 (-1725 2075)(-1725 2525);
WIRE 16 -1 (-1375 2075)(-1725 2075);
WIRE 16 -1 (-1775 2475)(-2175 2475);
FORCEPROP 2 LAST SIG_NAME M_KLM_RST_N
J 0
(-2150 2485);
DISPLAY 0.617021 (-2150 2485);
PAINT ORANGE (-2150 2485);
WIRE 16 -1 (-1375 2025)(-1775 2025);
WIRE 16 -1 (-1775 2025)(-1775 2475);
WIRE 16 -1 (-1825 2225)(-2550 2225);
FORCEPROP 2 LAST SIG_NAME FM_DIMM_EVENT_COD_N
J 0
(-2527 2243);
DISPLAY 0.617021 (-2527 2243);
PAINT ORANGE (-2527 2243);
WIRE 16 -1 (-1825 1975)(-1375 1975);
WIRE 16 -1 (-1825 1975)(-1825 2225);
WIRE 16 -1 (-175 1575)(-375 1575);
WIRE 16 -1 (-175 1875)(-375 1875);
WIRE 16 -1 (-175 1775)(-375 1775);
WIRE 16 -1 (-175 1675)(-375 1675);
WIRE 16 -1 (-175 1625)(-375 1625);
WIRE 16 -1 (-175 1725)(-375 1725);
WIRE 16 -1 (-175 1825)(-375 1825);
WIRE 16 -1 (-175 1925)(-375 1925);
WIRE 16 -1 (-175 1975)(-375 1975);
WIRE 16 -1 (-175 2025)(-375 2025);
WIRE 16 -1 (-175 1525)(-375 1525);
WIRE 16 -1 (-175 1425)(-375 1425);
WIRE 16 -1 (-175 1475)(-375 1475);
WIRE 16 -1 (-2225 1125)(-1375 1125);
FORCEPROP 2 LAST SIG_NAME FM_ADR_COMPLETE_KLM_N
J 0
(-2175 1135);
DISPLAY 0.617021 (-2175 1135);
PAINT ORANGE (-2175 1135);
WIRE 16 -1 (-1375 1925)(-2400 1925);
FORCEPROP 2 LAST SIG_NAME M_L_ALERT_N
J 0
(-2350 1935);
DISPLAY 0.617021 (-2350 1935);
PAINT ORANGE (-2350 1935);
WIRE 16 -1 (-1375 1575)(-2175 1575);
WIRE 16 -1 (-2175 1525)(-1375 1525);
FORCEPROP 2 LAST SIG_NAME SMB_DDR_KLM_VPP_SCL
J 0
(-2135 1535);
DISPLAY 0.617021 (-2135 1535);
PAINT ORANGE (-2135 1535);
WIRE 16 -1 (-2225 1275)(-1375 1275);
FORCEPROP 2 LAST SIG_NAME TP_CH_L_DIMM0_RFU_1
J 0
(-2175 1285);
DISPLAY 0.617021 (-2175 1285);
PAINT ORANGE (-2175 1285);
FORCEPROP 2 LASTPROP $XRERR UNIQUE?
J 0
(-2465 1275);
DISPLAY 0.638298 (-2465 1275);
PAINT MONO (-2465 1275);
DISPLAY INVISIBLE (-2465 1275);
WIRE 16 -1 (-2225 1225)(-1375 1225);
FORCEPROP 2 LAST SIG_NAME TP_CH_L_DIMM0_RFU_0
J 0
(-2175 1235);
DISPLAY 0.617021 (-2175 1235);
PAINT ORANGE (-2175 1235);
FORCEPROP 2 LASTPROP $XRERR UNIQUE?
J 0
(-2465 1225);
DISPLAY 0.638298 (-2465 1225);
PAINT MONO (-2465 1225);
DISPLAY INVISIBLE (-2465 1225);
WIRE 16 -1 (-2225 1325)(-1375 1325);
FORCEPROP 2 LAST SIG_NAME TP_CH_L_DIMM0_RFU_2
J 0
(-2175 1335);
DISPLAY 0.617021 (-2175 1335);
PAINT ORANGE (-2175 1335);
FORCEPROP 2 LASTPROP $XRERR UNIQUE?
J 0
(-2465 1325);
DISPLAY 0.638298 (-2465 1325);
PAINT MONO (-2465 1325);
DISPLAY INVISIBLE (-2465 1325);
WIRE 16 -1 (-3125 1425)(-3025 1425);
WIRE 16 -1 (-3025 1425)(-3025 1325);
WIRE 16 -1 (-1375 1425)(-3025 1425);
FORCEPROP 2 LAST SIG_NAME M_L_VREF
J 0
(-2125 1435);
DISPLAY 0.617021 (-2125 1435);
PAINT ORANGE (-2125 1435);
WIRE 16 -1 (-1375 1875)(-2375 1875);
FORCEPROP 2 LAST SIG_NAME M_L_ACT_N
J 0
(-2325 1885);
DISPLAY 0.617021 (-2325 1885);
PAINT ORANGE (-2325 1885);
DOT 1 (675 1975);
DOT 1 (-1475 1675);
DOT 1 (-1475 1775);
DOT 1 (-3025 1425);
DOT 1 (675 925);
DOT 1 (675 975);
DOT 1 (675 1025);
DOT 1 (675 1075);
DOT 1 (675 1125);
DOT 1 (675 1175);
DOT 1 (675 1325);
DOT 1 (675 1275);
DOT 1 (675 1225);
DOT 1 (675 1425);
DOT 1 (675 1375);
DOT 1 (675 1475);
DOT 1 (675 1525);
DOT 1 (675 1575);
DOT 1 (675 1625);
DOT 1 (675 1675);
DOT 1 (675 1725);
DOT 1 (675 1825);
DOT 1 (675 1775);
DOT 1 (675 1925);
DOT 1 (675 1875);
DOT 1 (675 2025);
DOT 1 (675 2075);
DOT 1 (675 2125);
DOT 1 (675 2275);
DOT 1 (675 2475);
DOT 1 (675 2425);
DOT 1 (675 2525);
DOT 1 (675 2575);
DOT 1 (2725 925);
DOT 1 (2725 1075);
DOT 1 (2725 1025);
DOT 1 (2725 975);
DOT 1 (2725 1125);
DOT 1 (2725 1175);
DOT 1 (2725 1325);
DOT 1 (2725 1225);
DOT 1 (2725 1275);
DOT 1 (2725 1425);
DOT 1 (2725 1375);
DOT 1 (2725 1475);
DOT 1 (2725 1575);
DOT 1 (2725 1525);
DOT 1 (2725 1625);
DOT 1 (2725 1675);
DOT 1 (2725 1725);
DOT 1 (2000 2575);
DOT 1 (2725 1825);
DOT 1 (2725 1775);
DOT 1 (2725 1975);
DOT 1 (2725 1925);
DOT 1 (2725 1875);
DOT 1 (2725 2025);
DOT 1 (2725 2075);
DOT 1 (2725 2175);
DOT 1 (2725 2125);
DOT 1 (2725 2225);
DOT 1 (2725 2275);
DOT 1 (2725 2325);
DOT 1 (2725 2375);
DOT 1 (2725 2475);
DOT 1 (2725 2425);
DOT 1 (2725 2525);
DOT 1 (2725 2575);
DOT 1 (2725 2625);
DOT 1 (2725 2725);
DOT 1 (2725 2675);
DOT 1 (2725 2775);
DOT 1 (2725 2825);
DOT 1 (2725 2875);
DOT 1 (2725 2975);
DOT 1 (2725 2925);
DOT 1 (2725 3125);
DOT 1 (2725 3025);
DOT 1 (2725 3075);
DOT 1 (2725 3175);
DOT 1 (4125 925);
DOT 1 (4125 1075);
DOT 1 (4125 1025);
DOT 1 (4125 975);
DOT 1 (4125 1125);
DOT 1 (4125 1175);
DOT 1 (4125 1325);
DOT 1 (4125 1225);
DOT 1 (4125 1275);
DOT 1 (4125 1375);
DOT 1 (4125 1425);
DOT 1 (4125 1475);
DOT 1 (4125 1575);
DOT 1 (4125 1525);
DOT 1 (4125 1675);
DOT 1 (4125 1625);
DOT 1 (4125 1725);
DOT 1 (4125 1825);
DOT 1 (4125 1775);
DOT 1 (4125 1975);
DOT 1 (4125 1925);
DOT 1 (4125 1875);
DOT 1 (4125 2075);
DOT 1 (4125 2025);
DOT 1 (4125 2225);
DOT 1 (4125 2175);
DOT 1 (4125 2125);
DOT 1 (4125 2275);
DOT 1 (4125 2325);
DOT 1 (4125 2375);
DOT 1 (4125 2475);
DOT 1 (4125 2425);
DOT 1 (4125 2575);
DOT 1 (4125 2525);
DOT 1 (4125 2625);
DOT 1 (4125 2725);
DOT 1 (4125 2675);
DOT 1 (4125 2875);
DOT 1 (4125 2775);
DOT 1 (4125 2825);
DOT 1 (4125 2975);
DOT 1 (4125 2925);
DOT 1 (4125 3125);
DOT 1 (4125 3075);
DOT 1 (4125 3025);
DOT 1 (4125 3175);
FORCENOTE
PVDDQ (SINGLE SIDE) CAP: 10UF X1, 22UF X50
(-1250 4950) 0;
DISPLAY LEFT (-1250 4950);
DISPLAY 1.021277 (-1250 4950);
PAINT PURPLE (-1250 4950);
FORCENOTE
PVTT CAP: 100UF X2, 47UF X1
(-1250 5000) 0;
DISPLAY LEFT (-1250 5000);
DISPLAY 1.021277 (-1250 5000);
PAINT PURPLE (-1250 5000);
FORCENOTE
PVDDQ (DOUBLE SIDE) CAP: 100UF X8, 47UF X41
(-1250 4900) 0;
DISPLAY LEFT (-1250 4900);
DISPLAY 1.021277 (-1250 4900);
PAINT PURPLE (-1250 4900);
FORCENOTE
PLACE CAP NEAR DIMM CONNECTOR
(-3663 877) 0;
DISPLAY LEFT (-3663 877);
DISPLAY 1.595745 (-3663 877);
PAINT PURPLE (-3663 877);
FORCENOTE
SMBUS ADDR: 0XA6
(-1325 834) 0;
DISPLAY LEFT (-1325 834);
DISPLAY 1.957447 (-1325 834);
PAINT PURPLE (-1325 834);
FORCENOTE
PVPP CAP: 10UF X12
(-1250 5050) 0;
DISPLAY LEFT (-1250 5050);
DISPLAY 1.021277 (-1250 5050);
PAINT PURPLE (-1250 5050);
FORCENOTE
CAP BETWEEN DIMM
(-1250 5125) 0;
DISPLAY LEFT (-1250 5125);
DISPLAY 1.276596 (-1250 5125);
PAINT PURPLE (-1250 5125);
QUIT
